G04 ================== begin FILE IDENTIFICATION RECORD ==================*
G04 Layout Name:  DAT6MTH3AD0_t6m_cm_d_brd_103112_274.brd*
G04 Film Name:    smb.art*
G04 File Format:  Gerber RS274X*
G04 File Origin:  Cadence Allegro 16.3-S048*
G04 Origin Date:  Tue Nov 26 10:18:26 2013*
G04 *
G04 Layer:  VIA CLASS/SOLDERMASK_BOTTOM*
G04 Layer:  PIN/SOLDERMASK_BOTTOM*
G04 Layer:  PACKAGE GEOMETRY/SOLDERMASK_BOTTOM*
G04 Layer:  MANUFACTURING/PHOTOPLOT_OUTLINE*
G04 Layer:  DRAWING FORMAT/TITLE_BLOCK*
G04 Layer:  DRAWING FORMAT/TITLE_DATA_SMB*
G04 Layer:  BOARD GEOMETRY/SOLDERMASK_BOTTOM*
G04 *
G04 Offset:    (0.00 0.00)*
G04 Mirror:    No*
G04 Mode:      Positive*
G04 Rotation:  0*
G04 FullContactRelief:  No*
G04 UndefLineWidth:     6.00*
G04 ================== end FILE IDENTIFICATION RECORD ====================*
%FSLAX25Y25*MOIN*%
%IR0*IPPOS*OFA0.00000B0.00000*MIA0B0*SFA1.00000B1.00000*%
%ADD47R,.034X.13*%
%ADD12R,.006X.012*%
%ADD43R,.008X.02*%
%ADD25R,.034X.17*%
%ADD10C,.03*%
%ADD19O,.044X.139*%
%ADD58C,.07*%
%ADD38C,.034*%
%ADD63C,.08*%
%ADD46C,.062*%
%ADD44R,.016X.009*%
%ADD40R,.0082X.016*%
%AMMACRO39*
21,1,.016,.0082,0.0,0.0,45.*%
%ADD39MACRO39*%
%ADD35R,.016X.0082*%
%ADD28C,.072*%
%ADD17C,.081*%
%ADD65C,.046*%
%ADD15C,.064*%
%ADD61C,.056*%
%ADD11C,.065*%
%ADD50C,.066*%
%ADD52C,.067*%
%ADD33C,.085*%
%ADD18C,.049*%
%ADD59R,.07X.07*%
%ADD69R,.062X.062*%
%ADD27R,.072X.072*%
%ADD22R,.081X.081*%
%ADD20C,.079*%
%ADD64R,.046X.046*%
%ADD14R,.064X.064*%
%ADD62R,.056X.056*%
%ADD60R,.065X.065*%
%ADD21R,.049X.049*%
%ADD56R,.068X.068*%
%ADD45R,.022X.024*%
%ADD34R,.024X.022*%
%ADD42R,.024X.022*%
%ADD24R,.022X.024*%
%ADD49R,.05X.017*%
%ADD55R,.017X.05*%
%ADD37R,.036X.032*%
%ADD16C,.14*%
%ADD36R,.032X.036*%
%ADD54C,.223*%
%ADD67C,.17*%
%ADD66R,.044X.036*%
%ADD53R,.066X.05*%
%ADD68C,.144*%
%ADD57R,.044X.054*%
%ADD41R,.063X.018*%
%ADD29C,.162*%
%ADD23R,.05X.066*%
%ADD26C,.118*%
%ADD48R,.057X.026*%
%ADD30C,.138*%
%ADD51C,.178*%
%ADD32R,.058X.048*%
%ADD31R,.048X.058*%
%ADD70C,.02*%
%ADD71C,.006*%
%ADD72C,.194*%
G75*
%LPD*%
G75*
G36*
G01X-44872Y237533D02*
G02I0J-5000D01*
G37*
G36*
G01Y253533D02*
G02I0J-5000D01*
G37*
G36*
G01X-32872Y131513D02*
G03I0J-800D01*
G37*
G36*
G01X-38872D02*
G03I0J-800D01*
G37*
G36*
G01X-35872D02*
G03I0J-800D01*
G37*
G36*
G01X-26872Y237533D02*
G02I0J-5000D01*
G37*
G36*
G01X-32872Y238833D02*
G03I0J-800D01*
G37*
G36*
G01X-38872D02*
G03I0J-800D01*
G37*
G36*
G01X-35872D02*
G03I0J-800D01*
G37*
G36*
G01X-33672Y239433D02*
X-39772D01*
Y241133D01*
X-33672D01*
X-32072D01*
X-31972D01*
Y239433D01*
X-32072D01*
X-33672D01*
G37*
G36*
G01X-26872Y253533D02*
G02I0J-5000D01*
G37*
G36*
G01X-38872Y748193D02*
G03I0J800D01*
G37*
G36*
G01X-32872D02*
G03I0J800D01*
G37*
G36*
G01X-35872D02*
G03I0J800D01*
G37*
G36*
G01X49526Y799372D02*
X328526D01*
Y821672D01*
X49526D01*
Y799372D01*
G37*
G36*
G01X77870Y357848D02*
G02I-5900J0D01*
G37*
G36*
G01X74604Y105511D02*
G02X122248I23822J1D01*
G01X122247Y85629D01*
G02X74605I-23821J198D01*
G01X74604Y105511D01*
G37*
G36*
G01Y719684D02*
G02X122248I23822J1D01*
G01X122247Y699802D01*
G02X74605I-23821J198D01*
G01X74604Y719684D01*
G37*
G36*
G01X153490Y647878D02*
G02I-5900J0D01*
G37*
G36*
G01X336926Y799372D02*
X379726D01*
Y821672D01*
X336926D01*
Y799372D01*
G37*
G36*
G01X393501Y377165D02*
G02X433271I19885J0D01*
G01Y357480D01*
G02X393501I-19885J0D01*
G01Y377165D01*
G37*
G36*
G01X407796Y799372D02*
X686796D01*
Y821672D01*
X407796D01*
Y799372D01*
G37*
G36*
G01X493670Y513674D02*
G02I-5900J0D01*
G37*
G36*
G01X583780Y395242D02*
G02I-5900J0D01*
G37*
G36*
G01X665155Y105315D02*
G02X712799I23822J0D01*
G01Y85630D01*
G02X665155I-23822J0D01*
G01Y105315D01*
G37*
G36*
G01Y719488D02*
G02X712799I23822J0D01*
G01Y699803D01*
G02X665155I-23822J0D01*
G01Y719488D01*
G37*
G36*
G01X699300Y758198D02*
G02I-5900J0D01*
G37*
G36*
G01X695196Y799372D02*
X737996D01*
Y821672D01*
X695196D01*
Y799372D01*
G37*
G36*
G01X751480Y62870D02*
G02I-5900J0D01*
G37*
%LPC*%
G75*
G36*
G01X108126Y98031D02*
G02X88726I-9700J-12204D01*
G03X89529Y99696I-1324J1665D01*
G01Y105512D01*
G02X107323I8897J0D01*
G01Y99696D01*
G03X108126Y98031I2127J0D01*
G37*
G36*
G01Y712204D02*
G02X88726I-9700J-12204D01*
G03X89529Y713869I-1324J1665D01*
G01Y719685D01*
G02X107323I8897J0D01*
G01Y713869D01*
G03X108126Y712204I2127J0D01*
G37*
G36*
G01X699023Y97551D02*
G02X678930I-10046J-11921D01*
G03X679687Y99177I-1370J1627D01*
G01Y105315D01*
G02X698267I9290J0D01*
G01Y99177D01*
G03X699023Y97551I2127J0D01*
G37*
G36*
G01Y711724D02*
G02X678930I-10046J-11921D01*
G03X679687Y713350I-1370J1627D01*
G01Y719488D01*
G02X698267I9290J0D01*
G01Y713350D01*
G03X699023Y711724I2127J0D01*
G37*
G54D72*
X413386Y377165D03*
%LPD*%
G75*
G54D10*
X-294532Y1044846D03*
X-281332D03*
X-287932D03*
X-267012Y1044916D03*
X20650Y546243D03*
X20350Y555807D03*
X16200Y566921D03*
X11980Y617956D03*
X15349Y614142D03*
X14550Y628297D03*
X13807Y634826D03*
X9300Y631472D03*
X33841Y9183D03*
X36588Y32278D03*
X34008Y91017D03*
X32260Y96899D03*
X33231Y556346D03*
X30672Y551245D03*
X23610Y568111D03*
X34440Y597285D03*
X28112Y591718D03*
X28185Y612088D03*
X30744Y617898D03*
X24168Y655750D03*
X37920Y651828D03*
X49890Y30392D03*
X51580Y17595D03*
X42205Y21518D03*
X54800Y25547D03*
X44010Y55170D03*
X54981Y59420D03*
X54101Y74252D03*
X51340Y69181D03*
X46570Y73891D03*
X47510Y109421D03*
X47420Y433725D03*
X53769Y513033D03*
X54988Y518683D03*
X49857Y520516D03*
X50630Y529281D03*
X50140Y550572D03*
X39540Y538464D03*
X50870Y564008D03*
X43467Y555938D03*
X49680Y579709D03*
X49620Y574212D03*
X47557Y588971D03*
X44507Y594082D03*
X40908Y589691D03*
X39370Y600956D03*
X42950Y612487D03*
X48540Y624953D03*
X52230Y614907D03*
X47480Y616848D03*
X46890Y633564D03*
X53751Y652029D03*
X44640Y651029D03*
X40980Y656396D03*
X56610Y20553D03*
X64190Y72841D03*
X61760Y107321D03*
X55230Y112521D03*
X63900Y112081D03*
X56190Y170026D03*
X57257Y180712D03*
X67853Y180744D03*
X68690Y175589D03*
X66570Y189983D03*
X68830Y215817D03*
X56287Y242872D03*
X63718Y239030D03*
X61945Y267579D03*
X66818Y297483D03*
X57994Y287655D03*
X61357Y477892D03*
X64480Y501596D03*
X62253Y522589D03*
X67369Y522993D03*
X70696Y527237D03*
X67260Y546688D03*
X65900Y566403D03*
X66262Y553344D03*
X65989Y578115D03*
X57710Y572918D03*
X57070Y580074D03*
X69766Y582525D03*
X57440Y585607D03*
X68630Y599945D03*
X61205Y623870D03*
X63570Y613914D03*
X63610Y618917D03*
X61205Y628870D03*
X56240Y630081D03*
X63650Y646957D03*
X61600Y653611D03*
X76030Y156152D03*
X82553Y185431D03*
X82030Y191733D03*
X73870Y205758D03*
X77239Y260814D03*
X81165Y257717D03*
X78373Y276029D03*
X72190Y297395D03*
X77368Y299206D03*
X83084Y389621D03*
X83245Y397913D03*
X85951Y410263D03*
X74291Y486665D03*
X83536Y498308D03*
X81635Y517104D03*
X85346Y512295D03*
X73057Y515286D03*
X72635Y508991D03*
X81491Y533191D03*
X80318Y544311D03*
X75380Y608914D03*
Y603914D03*
X101449Y194368D03*
X101020Y223348D03*
X95951Y376661D03*
X98470Y418834D03*
X91458Y511853D03*
X92422Y531081D03*
X98803Y531597D03*
X97268Y537055D03*
X96200Y616325D03*
X95310Y647481D03*
X97180Y786472D03*
X111220Y160923D03*
X106090Y167615D03*
X112530Y186363D03*
X106760Y175370D03*
X114920Y179082D03*
X108910Y193194D03*
X116960Y394023D03*
X114502Y401262D03*
X107531Y394023D03*
X109972Y509321D03*
X106650Y779581D03*
X102421Y785938D03*
X131068Y76588D03*
X129650Y250414D03*
Y255414D03*
X120144Y401104D03*
X126622Y401436D03*
X132344Y401278D03*
X132902Y394857D03*
X118124Y510811D03*
X124279Y523691D03*
X120300Y572512D03*
X121070Y670509D03*
X132050Y671817D03*
X133607Y686699D03*
X130260Y679836D03*
X132438Y704733D03*
X133490Y695470D03*
X131960Y720941D03*
X119900Y754021D03*
X125600Y759000D03*
X131900Y760900D03*
X125960Y785699D03*
X120090Y780618D03*
X141490Y19267D03*
X137872Y29551D03*
X139931Y40842D03*
X139932Y35310D03*
X135050Y53493D03*
X143857Y51943D03*
X149025Y51720D03*
X135290Y87664D03*
X148330Y258806D03*
X145200Y276468D03*
X138930Y278965D03*
X148350Y281769D03*
X134540Y267786D03*
X145720Y311336D03*
X135224Y323543D03*
X146100D03*
X145580Y316836D03*
X136506Y332193D03*
X139146Y400804D03*
X145284Y401507D03*
X142239Y422346D03*
X135300Y468444D03*
X146240Y472111D03*
X143543Y532024D03*
X141893Y544799D03*
X142087Y538145D03*
X146361Y555387D03*
X149050Y588044D03*
X148200Y669205D03*
X140110Y675907D03*
X139158Y686725D03*
X135280Y679212D03*
X138726Y696707D03*
X138198Y712628D03*
X144631Y735955D03*
X135470Y781697D03*
X145570Y780580D03*
X157877Y30674D03*
X152810Y29921D03*
X158165Y21300D03*
X159861Y36134D03*
X157010Y58963D03*
X164550Y61239D03*
X156440Y74863D03*
X151618Y83343D03*
X164280Y101810D03*
X164490Y127110D03*
X159190Y127781D03*
X152990Y248096D03*
X157690Y249918D03*
X154546Y256986D03*
X152634Y276809D03*
X149721Y292987D03*
X152733Y288517D03*
X158076Y290635D03*
X154581Y308767D03*
X151230Y330164D03*
X150918Y318134D03*
X150510Y336306D03*
X156448Y336629D03*
X162071Y336947D03*
X158605Y364565D03*
X161563Y432521D03*
X154370Y449930D03*
X159690Y465290D03*
X150547Y459363D03*
X162335Y512456D03*
X159196Y515612D03*
X159179Y521893D03*
X154126Y524411D03*
X154475Y530422D03*
X159180Y528227D03*
X162335Y543954D03*
X159185Y537654D03*
X162336Y550253D03*
X164259Y557273D03*
X161280Y581585D03*
X156480Y583315D03*
X150380Y602885D03*
X152442Y627881D03*
X157963Y633735D03*
X161981Y730784D03*
X163138Y778565D03*
X155170Y780656D03*
X160320Y786346D03*
X168961Y27073D03*
X180159Y40661D03*
X165336Y46126D03*
X167383Y93147D03*
X168850Y99251D03*
X169510Y106579D03*
X174710Y105699D03*
X177763Y121057D03*
X168170Y123367D03*
X173170D03*
X178040Y228978D03*
X167483Y239914D03*
X177891Y249324D03*
X175756Y257668D03*
X170501Y259161D03*
X178025Y279018D03*
X178810Y287263D03*
X174148Y289289D03*
X180410Y304866D03*
X172988Y305719D03*
X168110Y350642D03*
X174860Y362416D03*
X180430Y392969D03*
X180440Y398056D03*
X167527Y420268D03*
X179562Y424001D03*
X170683Y436834D03*
X170361Y428595D03*
X169728Y487664D03*
X165970Y497629D03*
X176909Y501153D03*
X168189Y514331D03*
X178085Y512456D03*
X173252Y515693D03*
X165707Y506156D03*
X172087Y510536D03*
X169615Y519216D03*
X178094Y531365D03*
X166297Y532416D03*
X169491Y529702D03*
X166837Y523486D03*
X174395Y527975D03*
X173513Y522854D03*
X168243Y542706D03*
X174930Y547106D03*
X169157Y548676D03*
X173163Y551903D03*
X169444Y558757D03*
X167105Y552882D03*
X178083Y553402D03*
X172889Y562710D03*
X175330Y578535D03*
X166930Y578435D03*
X166786Y569056D03*
X172430Y584035D03*
X177830Y583535D03*
X166570Y583874D03*
X179120Y639615D03*
X169930Y635329D03*
X172510Y639771D03*
X167810Y668131D03*
X171180Y683815D03*
X180820Y717914D03*
X175463Y720245D03*
X174954Y728404D03*
X167568Y743335D03*
X177070Y785736D03*
X177224Y777765D03*
X169860Y782086D03*
X191596Y27620D03*
X184928Y91847D03*
X189928D03*
X196653Y91837D03*
X196493Y105637D03*
X188203Y104567D03*
X194463Y122631D03*
X184050Y230139D03*
X184296Y241098D03*
X181176Y257643D03*
X183440Y269816D03*
X193245Y280285D03*
X189689Y268237D03*
X183198Y278034D03*
X188979Y273444D03*
X191970Y297731D03*
X192298Y286183D03*
X183254Y310663D03*
X183228Y317023D03*
X191159Y317171D03*
X190557Y325701D03*
X195530Y340946D03*
X192040Y333606D03*
X184953Y361563D03*
X182788Y352108D03*
X195420Y372406D03*
X192681Y377554D03*
X193590Y383383D03*
X196273Y403152D03*
X190700Y418325D03*
X182370Y439198D03*
X192527Y429049D03*
X189077Y438281D03*
X192741Y497930D03*
X184843Y533995D03*
X189252Y526236D03*
X191457Y531553D03*
X193466Y546886D03*
X186841Y545372D03*
X194709Y557353D03*
X181491Y557436D03*
X193080Y581235D03*
X182480Y566819D03*
X196740Y589735D03*
X189460Y587915D03*
X192130Y632235D03*
X184748Y639687D03*
X182480Y634585D03*
X191480Y639135D03*
X185993Y682670D03*
X191542Y691925D03*
X181950Y698191D03*
X188566Y722353D03*
X183566D03*
X193566Y722333D03*
X187570Y770605D03*
X192949Y771020D03*
X191081Y785766D03*
X183650Y774332D03*
X182500Y780786D03*
X189770Y778082D03*
X204978Y10605D03*
X204003Y91247D03*
X208908Y96975D03*
X205903Y101477D03*
X210623Y121267D03*
X207154Y175212D03*
X207070Y188978D03*
X205535Y234497D03*
Y228682D03*
X211935Y230585D03*
X205271Y240209D03*
X198685Y237385D03*
Y244085D03*
X210305Y259330D03*
X200977Y256305D03*
X208101Y273007D03*
X197850Y272666D03*
X197468Y289193D03*
X202687Y296024D03*
X198801Y318727D03*
X208000Y325200D03*
X206318Y334987D03*
X200687Y374520D03*
X206973Y361900D03*
X208529Y366783D03*
X201267Y403294D03*
X204584Y462478D03*
X197161Y465628D03*
X203628Y475993D03*
X197628Y489843D03*
X211609Y516553D03*
X205257Y528822D03*
X211287Y528547D03*
X212342Y536729D03*
X199539Y537112D03*
X204309Y539953D03*
X205286Y551130D03*
X211240Y572893D03*
X201510Y576885D03*
X197730Y572893D03*
X197709Y567464D03*
X210790Y566926D03*
X209940Y584893D03*
X198210Y611085D03*
X204024Y604135D03*
Y609135D03*
X208904Y611515D03*
X200380Y629085D03*
X199786Y618893D03*
X202510Y624005D03*
X208904Y616515D03*
X197480Y639815D03*
X203065Y638700D03*
X205221Y630886D03*
X205410Y661200D03*
X211560Y670575D03*
X199590Y682868D03*
X199350Y692724D03*
X196966Y700705D03*
X198566Y722353D03*
X209017Y722344D03*
X203611Y722303D03*
X199760Y763929D03*
X210250Y784919D03*
X202050D03*
X200550Y772046D03*
X206180Y777654D03*
X196886Y779156D03*
X206210Y771577D03*
X212350Y773283D03*
X215773Y90147D03*
X220200Y93561D03*
X226620Y89385D03*
X214320Y101978D03*
X220983Y106174D03*
X213908Y96975D03*
X219510Y101338D03*
X228138Y125802D03*
X226010Y233542D03*
X217135Y230585D03*
Y240785D03*
X216512Y258490D03*
X221784Y256315D03*
X219199Y288344D03*
X214657Y356205D03*
X223831Y359027D03*
X221280Y350255D03*
X214007Y362701D03*
X216687Y374434D03*
X222225Y364031D03*
X227745Y368007D03*
X220687Y370857D03*
X224759Y374125D03*
X214786Y388603D03*
X218090Y390891D03*
X215120Y399654D03*
X214406Y395539D03*
X223085Y401702D03*
X222419Y479933D03*
X218040Y473853D03*
X226255Y472579D03*
X227284Y502591D03*
X213209Y498353D03*
X224209Y491853D03*
X217609Y516353D03*
X219328Y528823D03*
X226909Y528053D03*
X223376Y523322D03*
X225087Y534356D03*
X215946Y544202D03*
X218950Y565589D03*
X227100Y580916D03*
X227838Y566913D03*
X219960Y596373D03*
Y601373D03*
X215699Y625977D03*
X216107Y637977D03*
X228290Y629893D03*
X218240Y674433D03*
X217530Y715305D03*
X221320Y720698D03*
X213310Y719064D03*
X222710Y713706D03*
X216820Y723301D03*
X219520Y770824D03*
X214160Y779627D03*
X226250Y785923D03*
X218270Y785657D03*
X220960Y778561D03*
X226670Y773299D03*
X243373Y88767D03*
X239563Y92077D03*
X233083Y94817D03*
X242913Y106157D03*
X233138Y125802D03*
X232948Y234047D03*
X236710Y244042D03*
X242460Y237591D03*
X237654Y249719D03*
X231710Y240242D03*
X230318Y249425D03*
X228495Y256384D03*
X236618Y270187D03*
X240567Y293811D03*
X240925Y306257D03*
X228432Y321468D03*
X230253Y328616D03*
X232873Y342946D03*
X235220Y348277D03*
X240241Y352958D03*
X228419Y356855D03*
X233635Y357082D03*
X241179Y347675D03*
X230010Y373300D03*
X237578Y369584D03*
X233136Y367070D03*
X243078Y368384D03*
X231257Y362218D03*
X236430Y393470D03*
X231461Y462591D03*
X243471Y460292D03*
X238430Y460338D03*
X228820Y467780D03*
X239700Y486907D03*
X234209Y480953D03*
X228604Y479682D03*
X234909Y489653D03*
X236909Y494453D03*
X236085Y500866D03*
X242502Y496300D03*
X240473Y549168D03*
X242834Y564253D03*
X235307Y566357D03*
X232088Y570503D03*
X241928Y570263D03*
X229269Y597682D03*
X242830Y597415D03*
X234370Y593242D03*
X242796Y589749D03*
X236780Y628738D03*
X229199Y642180D03*
X243693Y632254D03*
X238420Y642148D03*
X229584Y652668D03*
X237451Y652761D03*
X243596Y671772D03*
X229895Y671672D03*
X237275Y679609D03*
X236680Y700668D03*
X242680Y712337D03*
X234960Y714064D03*
X234910Y720816D03*
X238470Y770074D03*
X236180Y786517D03*
X242230Y774803D03*
X231460Y780174D03*
X234011Y772902D03*
X240080Y779908D03*
X258300Y22289D03*
X252683Y105867D03*
X253558Y95038D03*
X256133Y99347D03*
X248558Y95038D03*
X249453Y114307D03*
X244970Y176856D03*
X246003Y197877D03*
X254221Y230582D03*
X256492Y222466D03*
X254418Y240407D03*
X244526Y258705D03*
X256980Y299300D03*
X250469Y305798D03*
X251207Y329651D03*
X251491Y357134D03*
X246410Y348948D03*
X245258Y358468D03*
X258818Y349693D03*
X249410Y368527D03*
X244595Y363535D03*
X256331Y371006D03*
X254445Y364991D03*
X251126Y373722D03*
X254813Y427018D03*
X246465Y464893D03*
X251780Y460883D03*
X257568Y461513D03*
X246509Y486753D03*
X254999Y485763D03*
X250322Y493466D03*
X256809Y496153D03*
X244509Y491353D03*
X254809Y491153D03*
X248609Y498353D03*
X258965Y526457D03*
X255710Y574383D03*
X259678Y581553D03*
X249462Y648383D03*
X257271Y671772D03*
X244780Y682521D03*
X259170Y705138D03*
X258570Y722981D03*
X249190Y769760D03*
X256650Y770638D03*
Y778342D03*
X247900Y778823D03*
X252470Y785797D03*
X244910Y785782D03*
X271421Y7319D03*
X262955Y12663D03*
X266111Y29229D03*
X265789Y20990D03*
X268809Y16400D03*
X274990Y16396D03*
X272245Y89585D03*
X263703Y93847D03*
X262473Y106937D03*
X264980Y121886D03*
X264987Y205682D03*
X260108Y240376D03*
X267118Y245587D03*
X270260Y237037D03*
X273521Y265849D03*
X263774Y256464D03*
X272464Y259964D03*
X261024Y280657D03*
X261463Y296111D03*
X270444Y286183D03*
X268299Y306992D03*
X261915Y302033D03*
X262700Y325494D03*
X263173Y331794D03*
X260970Y343563D03*
X273871Y336662D03*
X269716Y349689D03*
X269886Y358753D03*
X260536Y374216D03*
X270293Y363972D03*
X268118Y374558D03*
X270796Y386643D03*
X263419Y393450D03*
X265162Y401391D03*
X272220Y401343D03*
X274180Y424966D03*
X266822Y443297D03*
X263807Y461234D03*
X260609Y486153D03*
X266205Y483343D03*
X272209Y485753D03*
X273841Y497993D03*
X264909Y498153D03*
X260109Y500153D03*
X263924Y491754D03*
X265009Y515555D03*
X263309Y531253D03*
X266098Y561963D03*
X269609Y576413D03*
X274309Y574653D03*
X261175Y569054D03*
X263792Y574203D03*
X268009Y570953D03*
X273480Y589201D03*
X269428Y622966D03*
X266610Y654171D03*
X261890Y664761D03*
X265550Y668415D03*
X274360Y673831D03*
X267240Y682519D03*
X269420Y677062D03*
X267124Y707892D03*
X273510Y699749D03*
X266170Y694826D03*
X260680Y712988D03*
X271210Y718000D03*
X264600Y723086D03*
X263430Y770417D03*
X275440Y770793D03*
X264340Y778780D03*
X272175Y783074D03*
X266850Y785971D03*
X269890Y773268D03*
X260000Y785233D03*
X284505Y30676D03*
X287766Y21289D03*
X278245Y31043D03*
X276603Y92119D03*
X287423Y91857D03*
X283383Y136155D03*
X284603Y210533D03*
X279161Y237817D03*
X276904Y252550D03*
X282166Y262922D03*
X278811Y259135D03*
X281767Y277742D03*
X290363Y286082D03*
X281818Y290787D03*
X284574Y305700D03*
X276282Y306927D03*
X275832Y329303D03*
X289822Y333092D03*
X281205Y340997D03*
X289191Y341348D03*
X280042Y358589D03*
X275902Y355665D03*
X277040Y376172D03*
X286550Y374402D03*
X281450Y373151D03*
X285390Y390550D03*
X287067Y402358D03*
X276626Y442913D03*
X276347Y459741D03*
X287588Y482033D03*
X284024Y502595D03*
X290323D03*
X281749Y531351D03*
X279658Y574443D03*
X285530Y573002D03*
X283650Y589044D03*
X287997Y649064D03*
X280880Y650295D03*
X278699Y656491D03*
X289365Y673719D03*
X279843Y675688D03*
X282391Y687978D03*
X275710Y681593D03*
X289248Y680521D03*
X286798Y704143D03*
X278370Y705093D03*
X277475Y695723D03*
X285130Y714433D03*
X275880Y722141D03*
X285880Y722268D03*
X280210Y734805D03*
X288390Y734796D03*
X284532Y747493D03*
X275627Y777692D03*
X281930Y773190D03*
X286722Y785929D03*
X278549Y786377D03*
X289028Y778380D03*
X301870Y92072D03*
X296870D03*
X291927Y102991D03*
X296927D03*
X302930Y132994D03*
X299776Y248010D03*
X301511Y262204D03*
X296210Y253187D03*
X292710Y266542D03*
X297810Y280709D03*
X294382Y291966D03*
X291853Y327033D03*
X305880Y339046D03*
X299410Y331201D03*
X300530Y337075D03*
X296218Y353688D03*
X295527Y359812D03*
X293290Y389737D03*
X299533Y394056D03*
X300040Y459733D03*
X298218Y478853D03*
X297370Y498563D03*
X305708Y503043D03*
X304410Y572782D03*
X294909Y578653D03*
X301796Y603917D03*
X298303Y613184D03*
X293843Y642536D03*
X297394Y657033D03*
X302772Y659604D03*
X300880Y664296D03*
X295890Y662662D03*
X295950Y689520D03*
X293068Y677108D03*
X296858Y702544D03*
X297300Y697221D03*
X293300Y718944D03*
X298590Y733669D03*
X293480Y725080D03*
X293440Y748380D03*
X291340Y771217D03*
X295100Y786269D03*
X299249Y771403D03*
X304740Y777277D03*
X297280Y778936D03*
X302440Y784731D03*
X311553Y92347D03*
X310850Y99620D03*
X320740Y98599D03*
X311290Y247249D03*
X315019Y295263D03*
X309347Y291940D03*
X309798Y306104D03*
X311740Y325839D03*
X316670Y316560D03*
X314550Y331564D03*
X318480Y335039D03*
X319288Y350376D03*
X307410Y348380D03*
X313222Y374229D03*
X321297Y367739D03*
X310484Y383312D03*
X317140Y421775D03*
X321910Y410139D03*
X320080Y512736D03*
X320094Y604114D03*
X320512Y613603D03*
X308741Y623871D03*
X311311Y618197D03*
X316183Y644594D03*
X316190Y649621D03*
Y668863D03*
X316184Y662630D03*
Y687630D03*
X316165Y693404D03*
X319620Y716403D03*
X308430Y718693D03*
X321930Y724895D03*
X314930Y724533D03*
X307146Y769416D03*
X315020Y780559D03*
X320657Y779595D03*
X320440Y771967D03*
X311440Y774049D03*
X317020Y786486D03*
X310050Y785923D03*
X335668Y92822D03*
X330668D03*
X325360Y92517D03*
X325970Y98817D03*
X327190Y103818D03*
X337630Y106304D03*
X334720Y102184D03*
X331583Y128717D03*
X331867Y291367D03*
X334622Y302861D03*
X336720Y310846D03*
X337293Y316660D03*
X327058Y358376D03*
X336850Y380332D03*
X331090Y424304D03*
X331900Y419317D03*
X336740Y417069D03*
X322986Y467109D03*
X330115Y490303D03*
X335162Y502791D03*
X326740Y495763D03*
X329672Y502057D03*
X326170Y518386D03*
X335860Y516486D03*
X329348Y533403D03*
X332408Y544097D03*
X336057Y575657D03*
X323931Y589733D03*
X323346Y621930D03*
X337070Y639759D03*
X326350Y638968D03*
X324120Y703114D03*
X332666Y706026D03*
X325560Y713391D03*
X330940Y719125D03*
X338460Y724585D03*
X328280Y770057D03*
X326280Y775980D03*
X337800Y774677D03*
X322871Y785090D03*
X349490Y57698D03*
X352578Y74292D03*
X339750Y73383D03*
X353713Y93057D03*
X344873Y94847D03*
X340450Y101914D03*
X343743Y120967D03*
X351503Y127972D03*
X343220Y280416D03*
X341693Y286010D03*
X342754Y295326D03*
X340792Y307107D03*
X339487Y301038D03*
X351650Y420270D03*
X345270Y452745D03*
X339506Y482841D03*
X348220Y486484D03*
X348870Y501571D03*
X343420Y497966D03*
X340902Y503742D03*
X341512Y512429D03*
X350902Y512520D03*
X346350Y517286D03*
X351964Y599332D03*
X351720Y644191D03*
X348480Y638558D03*
X351730Y649206D03*
Y675057D03*
Y663450D03*
X351720Y670018D03*
X339300Y716800D03*
X342230Y720936D03*
X344710Y785782D03*
X350450Y784982D03*
X338642Y785716D03*
X343370Y779720D03*
X345100Y771906D03*
X350630Y777187D03*
X363025Y12926D03*
X366159Y21822D03*
X361930Y60031D03*
X367300Y60442D03*
X367776Y91746D03*
X358343Y90948D03*
X361470Y101757D03*
X367350Y123927D03*
X356835Y313894D03*
X367220Y303202D03*
X369934Y322946D03*
X364580Y391273D03*
X365850Y414874D03*
X354565Y451562D03*
X354750Y445325D03*
X369507Y464391D03*
X368825Y539776D03*
X361473Y620588D03*
X364950Y639095D03*
X365990Y645272D03*
X367870Y650239D03*
X364980Y655266D03*
X363340Y650512D03*
X365620Y663069D03*
X365380Y668972D03*
X364765Y687963D03*
X365090Y676923D03*
X364115Y692990D03*
X367520Y701710D03*
X357830Y718682D03*
X364750Y727821D03*
X364090Y748565D03*
X357610Y748302D03*
X354870Y771388D03*
X360160Y775523D03*
X363300Y781303D03*
X367904Y778327D03*
X356600Y782086D03*
X362264Y786424D03*
X381907Y21507D03*
X383280Y59940D03*
X376006Y60991D03*
X372776Y91746D03*
X380483Y99047D03*
X378733Y105987D03*
X384863Y95437D03*
X378183Y124904D03*
X372080Y330574D03*
X382190Y388077D03*
X371260Y412879D03*
X371950Y430527D03*
X375190Y463996D03*
X381239Y467171D03*
X371080Y481589D03*
X376540Y498385D03*
X383617Y517862D03*
X376528Y520138D03*
X379733Y549392D03*
X370309Y550322D03*
X382333Y540414D03*
X385573Y629998D03*
X373218Y634217D03*
X382580Y637413D03*
X385145Y652326D03*
X383627Y646254D03*
X379492Y650239D03*
X376089Y646156D03*
X373680Y662417D03*
X376087Y670156D03*
X379461Y675246D03*
X384868Y675433D03*
X379462Y666156D03*
X377673Y686355D03*
X377682Y681355D03*
X377681Y694244D03*
X377679Y701168D03*
X377669Y706237D03*
X372360Y704766D03*
X376770Y734898D03*
X373500Y748457D03*
X370130Y770105D03*
X373370Y783928D03*
X397655Y21336D03*
X397790Y61360D03*
X390355Y75775D03*
X392493Y92647D03*
X400163Y99177D03*
X391310Y99570D03*
X398088Y128455D03*
X393088D03*
X399598Y260251D03*
X398258Y252341D03*
X394378Y260501D03*
X393458Y282931D03*
X392508Y275581D03*
X398038Y292571D03*
X390080Y331575D03*
X395740Y407528D03*
X392076Y470970D03*
X388982Y496939D03*
X396558Y522251D03*
X396470Y527847D03*
X396590Y549310D03*
X399590Y553502D03*
X393596Y567630D03*
X401191Y603637D03*
X391447Y611973D03*
X394389Y604053D03*
X399223Y644930D03*
X394380Y643389D03*
X389856Y645705D03*
X391790Y715248D03*
X400730Y721954D03*
X410713Y76187D03*
X417248Y266301D03*
X404738Y260421D03*
X403148Y270191D03*
X403628Y292201D03*
X406352Y471405D03*
X410607Y485620D03*
X413138Y504813D03*
X407865Y516627D03*
X412088Y521721D03*
X407776Y527426D03*
X405954Y532502D03*
X404336Y545280D03*
X411058Y545353D03*
X408486Y537333D03*
X408736Y551529D03*
X413342Y556219D03*
X412783Y605500D03*
X416454Y621319D03*
X413105Y613739D03*
X403904Y618333D03*
X403970Y642364D03*
X406100Y631851D03*
X413535Y646804D03*
X411982Y660285D03*
X413718Y655267D03*
X415218Y664203D03*
X411675Y672654D03*
X411065Y667516D03*
X416938Y669947D03*
X414183Y686151D03*
X413643Y680004D03*
X414318Y700979D03*
X414080Y721334D03*
X409010Y726147D03*
X415780Y747078D03*
X414130Y779689D03*
X421893Y123537D03*
X421640Y223403D03*
X428405Y245194D03*
X424961Y241203D03*
X418905Y245694D03*
X426992Y250016D03*
X422528Y253531D03*
X426335Y267062D03*
X420858Y261331D03*
X427817Y258829D03*
X421728Y279141D03*
X428748Y275222D03*
X418588Y286681D03*
X421128Y292601D03*
X423178Y284601D03*
X427909Y286759D03*
X427468Y292287D03*
X428747Y463314D03*
Y468770D03*
X422050Y517028D03*
X418660Y541421D03*
X428039Y548119D03*
X421461Y547703D03*
X420883Y556729D03*
X431145Y556608D03*
X429340Y596874D03*
X431520Y607039D03*
X432180Y647458D03*
X425334Y656419D03*
X421080Y665945D03*
X418381Y690878D03*
X427230Y707377D03*
X429240Y721014D03*
X422010Y766690D03*
X421690Y779548D03*
X417880Y786361D03*
X425540Y786506D03*
X431290Y785484D03*
X428250Y772054D03*
X426900Y779752D03*
X417552Y772874D03*
X446920Y78358D03*
X447715Y97926D03*
X444550Y184057D03*
X441580Y250730D03*
X443212Y240957D03*
X441792Y259473D03*
X445890Y283317D03*
X443240Y401984D03*
X437887Y471073D03*
X444920Y485259D03*
X437716Y476295D03*
X445199Y494590D03*
X439749Y506523D03*
X439762Y515540D03*
Y523757D03*
X434605Y521488D03*
X445838Y538085D03*
X441063Y540563D03*
X437832Y556374D03*
X442240Y553337D03*
X435319Y600123D03*
X437120Y612933D03*
X448460Y625960D03*
X437509Y648996D03*
X444700Y651900D03*
X447210Y665143D03*
X447161Y673564D03*
X444458Y669350D03*
X440688Y684438D03*
X442920Y678095D03*
X440688Y689438D03*
X440690Y702386D03*
X440688Y694438D03*
X440660Y712065D03*
X436560Y770904D03*
X444370Y770152D03*
X434540Y778500D03*
X442100Y777623D03*
X446510Y784890D03*
X441006Y785297D03*
X458120Y44721D03*
X464170Y56436D03*
X461594Y99342D03*
X449538Y105144D03*
X453940Y98586D03*
X461880Y150596D03*
X462790Y183489D03*
X450650Y203785D03*
X450576Y234431D03*
X453620Y245162D03*
X451790Y300129D03*
X451504Y529734D03*
X450540Y521331D03*
X463991Y531504D03*
X456722Y529536D03*
X463031Y543563D03*
X453917Y550069D03*
X450367Y540720D03*
X453700Y545047D03*
X453854Y555069D03*
X462270Y612911D03*
X464050Y633877D03*
X458903Y644884D03*
X463178Y647483D03*
X460587Y669424D03*
X457138Y663251D03*
X449060Y721761D03*
X461565Y785806D03*
X463750Y780452D03*
X454120Y785923D03*
X454399Y771873D03*
X457530Y779016D03*
X449610Y777933D03*
X475030Y63879D03*
X470324Y133424D03*
X474813Y162220D03*
X467473Y159766D03*
X473951Y157235D03*
X473950Y172124D03*
X475770Y186451D03*
X471300Y201900D03*
X466200Y207300D03*
X464810Y311253D03*
X480118Y479107D03*
Y474107D03*
X471804Y561085D03*
Y556085D03*
X468740Y585897D03*
X469890Y596580D03*
X476320Y629280D03*
X469229Y638135D03*
X475820Y635422D03*
X468810Y652180D03*
X479512Y649436D03*
X466980Y667059D03*
X479354Y677054D03*
X466070Y774997D03*
X469360Y780411D03*
X475620Y779095D03*
X478290Y786393D03*
X471780Y786300D03*
X486810Y60785D03*
X488438Y109623D03*
X494355Y108674D03*
X490175Y122348D03*
X484350Y112811D03*
X487857Y152147D03*
X492424Y142234D03*
X494467Y148867D03*
X490130Y163086D03*
X493670Y171871D03*
X489040Y169483D03*
X482980Y181071D03*
X488850Y175419D03*
X487839Y194142D03*
X488017Y203716D03*
X486370Y189279D03*
X492700Y223800D03*
X484169Y272867D03*
X486300Y422150D03*
X481300D03*
X482880Y467935D03*
Y462935D03*
X490334Y497342D03*
X483209Y545250D03*
Y550250D03*
X490661Y547148D03*
X489962Y540849D03*
X483838Y566194D03*
Y556148D03*
Y561148D03*
Y571194D03*
X485738Y587125D03*
X490738D03*
X481340Y593296D03*
X494238Y600441D03*
X490600Y608136D03*
X489800Y600200D03*
X487832Y624429D03*
X480310Y642224D03*
X481253Y654837D03*
X484700Y660355D03*
X482398Y673087D03*
X482544Y668042D03*
X490120Y662703D03*
X481227Y685366D03*
Y691366D03*
X490900Y706145D03*
X481227Y696366D03*
X495560Y694781D03*
X488180Y719244D03*
X490890Y714898D03*
X488090Y710545D03*
X488250Y786657D03*
X480770Y778125D03*
X485870Y776087D03*
X491720Y776713D03*
X495110Y771733D03*
X502900Y57670D03*
X500310Y109211D03*
X497430Y124024D03*
X504750Y111749D03*
X509691Y112938D03*
X509710Y127269D03*
X500215Y136449D03*
X502183Y156709D03*
X496360Y167221D03*
X498940Y179744D03*
X510000Y173500D03*
X509100Y191900D03*
X499225Y205296D03*
X506234Y207368D03*
X498867Y227773D03*
X504160Y255584D03*
X497111Y388567D03*
X502111D03*
X505819Y417473D03*
X498238Y417825D03*
X499551Y429636D03*
X502494Y436725D03*
X509486Y433829D03*
X506456Y446928D03*
X502938Y463823D03*
X498119Y470011D03*
X511230Y499059D03*
X506230D03*
X504613Y525200D03*
X503338Y549825D03*
Y544825D03*
X500538Y588525D03*
Y600925D03*
X508400Y617803D03*
X502080Y622999D03*
X505690Y654419D03*
X508061Y645381D03*
X504295Y649612D03*
X504114Y670830D03*
X496453Y670876D03*
X501914Y675624D03*
X504241Y665809D03*
X497320Y665216D03*
X496577Y684553D03*
X505580Y679105D03*
X496277Y678185D03*
X501540Y681970D03*
X506409Y691373D03*
X497350Y699767D03*
X506092Y697575D03*
X501604Y733003D03*
X501890Y746663D03*
X497880Y785893D03*
X509000Y775415D03*
X502480Y782382D03*
X507935Y785704D03*
X511770Y779940D03*
X499270Y776431D03*
X504440Y772548D03*
X513120Y72069D03*
X512878Y108635D03*
X519625Y108543D03*
X526835Y108314D03*
X516146Y113121D03*
X522111Y113310D03*
X518640Y125539D03*
X514510Y133093D03*
X522448Y137674D03*
X523100Y153100D03*
X512600Y147500D03*
X523100Y159400D03*
X515600Y172800D03*
X521320Y178184D03*
X516100Y178100D03*
X526621Y177079D03*
X515231Y191334D03*
X520015Y194584D03*
X523593Y198171D03*
X512200Y196000D03*
X520068Y207142D03*
X516551Y214987D03*
X517670Y247527D03*
X515675Y254098D03*
X525480Y268959D03*
X527438Y340353D03*
X517617Y422944D03*
X514820Y417617D03*
X526440Y422428D03*
X527300Y417368D03*
X517929Y439676D03*
X512867Y443679D03*
X525638Y484023D03*
X524848Y548755D03*
X513998Y568675D03*
X525808Y582665D03*
X514058Y605055D03*
X526300Y623621D03*
X518920Y615387D03*
X514320Y641085D03*
X525692Y654862D03*
X517328Y655529D03*
X521516Y650576D03*
X517222Y673917D03*
X518800Y665776D03*
X515541Y661845D03*
X526430Y664730D03*
X515429Y692278D03*
X526600Y679117D03*
X517888Y687901D03*
X527111Y686052D03*
X515429Y697278D03*
X512548Y722093D03*
X512610Y747115D03*
X519560Y779689D03*
X514430Y785721D03*
X525110Y774395D03*
X519440Y772861D03*
X523683Y786110D03*
X539510Y108742D03*
X536955Y100257D03*
X535960Y112850D03*
X527613Y113373D03*
X538968Y168838D03*
X539500Y196500D03*
X536232Y192086D03*
X529592Y192999D03*
X533474Y196500D03*
X541657Y207645D03*
X532320Y209470D03*
X534208Y227832D03*
X528105Y230594D03*
X535772Y250076D03*
X539267Y267102D03*
X530119Y280101D03*
X533913Y402151D03*
X541650Y422280D03*
X529968Y440216D03*
X529028Y430469D03*
X535352Y440414D03*
X540141Y442994D03*
X537378Y564875D03*
X529408Y603485D03*
X542848Y602975D03*
X535048Y602885D03*
X532420Y615484D03*
X542424Y654821D03*
X536557Y655498D03*
X529525Y669349D03*
X529899Y661020D03*
X539734Y675020D03*
X539577Y721891D03*
X540062Y708779D03*
X531557Y786392D03*
X537320Y786298D03*
X539650Y780942D03*
X529300Y771341D03*
X543075Y775577D03*
X533600Y778780D03*
X527620Y781318D03*
X557995Y110244D03*
X550490Y112989D03*
X552173Y138528D03*
X550599Y132596D03*
X550550Y151682D03*
X558059Y154254D03*
X558348Y142511D03*
X551464Y143862D03*
X550604Y168072D03*
X550370Y157461D03*
X557668Y176534D03*
X551395Y174172D03*
X544500Y197500D03*
X546000Y192000D03*
X557909Y207537D03*
X547148Y220220D03*
X554663Y230782D03*
X545703Y245725D03*
X545981Y236287D03*
X545116Y266847D03*
X547929Y258102D03*
X545223Y276895D03*
X557207Y280328D03*
X555072Y289563D03*
X552090Y388953D03*
X553230Y407251D03*
X549574Y432582D03*
X546384Y445107D03*
X547488Y452373D03*
X554550Y469674D03*
X545513Y469740D03*
X547638Y462356D03*
X546038Y457523D03*
X546250Y490302D03*
X554860Y531701D03*
X549920Y527242D03*
X550149Y604639D03*
X543400Y625963D03*
X552350Y614028D03*
X558281Y637840D03*
X551030Y637200D03*
X543400Y635615D03*
X549314Y647594D03*
X551230Y652844D03*
X551283Y670800D03*
Y699243D03*
X544934Y720820D03*
X550535Y721903D03*
X555551Y722342D03*
X557488Y713709D03*
X553725Y717251D03*
X550004Y709559D03*
X555062Y708679D03*
X545062D03*
X557978Y734053D03*
X545300Y783152D03*
X550940Y771858D03*
X554870Y779438D03*
X549350Y777416D03*
X552830Y785015D03*
X558360Y775757D03*
X569559Y103123D03*
X566105Y112518D03*
X564076Y145372D03*
X563410Y165289D03*
X562195Y159015D03*
X563129Y178369D03*
X569682Y195199D03*
X563775Y227018D03*
X564274Y279395D03*
X561525Y298192D03*
X560865Y285434D03*
X565953Y301635D03*
X565310Y412700D03*
X572440Y464323D03*
Y469323D03*
X562340Y484252D03*
X567791Y528325D03*
X562308Y536895D03*
X566298Y548465D03*
X563188Y541925D03*
X566338Y554235D03*
X561174Y564471D03*
X574738Y579525D03*
X565858Y576195D03*
X561198Y581793D03*
X566378Y567725D03*
X561608Y571775D03*
X574537Y591325D03*
X565398Y584765D03*
X568163Y595115D03*
X561568Y589355D03*
X574071Y606204D03*
X568930Y607754D03*
X574730Y625521D03*
X565647Y637705D03*
X565556Y632431D03*
X571790Y646799D03*
X559440Y650767D03*
X566950Y659439D03*
X571494Y663571D03*
X565168Y664614D03*
Y674614D03*
Y669614D03*
Y684614D03*
Y679614D03*
Y689614D03*
Y694614D03*
Y699614D03*
X560544Y718091D03*
X569604Y721248D03*
X574190Y717805D03*
X564319Y721587D03*
X562540Y713454D03*
X560062Y708679D03*
X570614Y713237D03*
X565062Y708679D03*
X566798Y734023D03*
X569680Y771106D03*
X560150Y781347D03*
X571230Y785131D03*
X562700Y772391D03*
X572720Y777184D03*
X567210Y778530D03*
X563053Y785792D03*
X578938Y103123D03*
X580501Y138336D03*
X583829Y132232D03*
X587968Y138765D03*
X581565Y154969D03*
X579897Y161355D03*
X582792Y167632D03*
X581915Y179955D03*
X588692Y192809D03*
X585580Y210516D03*
X579707Y229395D03*
X585579Y230095D03*
X585874Y281995D03*
X588607Y305034D03*
X576650Y311446D03*
X581650D03*
X585984Y323246D03*
X589070Y423525D03*
X578830Y448192D03*
X585013Y547959D03*
X576208Y542405D03*
X575838Y548935D03*
X577778Y556355D03*
X588780Y611056D03*
X586810Y603344D03*
X588780Y616056D03*
X583930Y652439D03*
X577217Y652002D03*
X576987Y660180D03*
X580637Y663629D03*
X584312Y710716D03*
X583440Y724927D03*
X577570Y734118D03*
X586676Y786016D03*
X583880Y779251D03*
X578330Y785014D03*
X587170Y773768D03*
X579240Y775147D03*
X605070Y123991D03*
X600118Y112568D03*
X592938Y117657D03*
Y140689D03*
Y133232D03*
X594938Y127893D03*
X591707Y230162D03*
X595374Y236795D03*
X594374Y271395D03*
X596574Y276393D03*
X593607Y305034D03*
X590984Y323246D03*
X604338Y338285D03*
X597440Y391690D03*
X590720Y456076D03*
X591100Y450128D03*
X605800Y463167D03*
X603819Y485332D03*
X605798Y501238D03*
X596751Y532108D03*
X603010Y527908D03*
X604820Y555040D03*
X592437Y566543D03*
X601043Y567781D03*
X605396Y590552D03*
X605286Y584152D03*
X593867Y595695D03*
X602314Y607641D03*
Y602641D03*
X593867Y600695D03*
X605430Y622721D03*
X591279Y656223D03*
X596998Y658008D03*
X600736Y668425D03*
X600719Y675156D03*
X597300Y663128D03*
X600690Y691896D03*
X600727Y681876D03*
Y686876D03*
X604220Y703774D03*
X592960Y703291D03*
X601856Y711479D03*
X595950Y708997D03*
X594170Y719290D03*
X603938Y753623D03*
X602424Y778468D03*
X591460Y780096D03*
X596590Y786204D03*
X606270Y774615D03*
X597530Y780191D03*
X592480Y771514D03*
X610543Y107678D03*
X617925Y114064D03*
X613432Y153528D03*
X610415Y237441D03*
X617474Y246495D03*
X617778Y238873D03*
X617274Y257595D03*
X617374Y262695D03*
X613640Y336986D03*
X607671Y344818D03*
X611848Y359784D03*
X607855Y352341D03*
X618581Y354818D03*
X620238Y364369D03*
X609078Y388557D03*
Y393557D03*
X612641Y397478D03*
Y402478D03*
X611050Y423087D03*
X616258Y422211D03*
X610580Y448662D03*
X610010Y456581D03*
X617980Y460408D03*
X621760Y526967D03*
X613470Y537495D03*
X610070Y557588D03*
X610821Y566494D03*
X621937Y567143D03*
X609026Y579132D03*
X617270Y580443D03*
X611520Y596594D03*
X611254Y617943D03*
X615690Y625536D03*
X616730Y633290D03*
X611572Y629894D03*
X613796Y648705D03*
X612950Y656140D03*
X613200Y661577D03*
X620160Y670594D03*
X615940Y666862D03*
X616031Y675149D03*
X612670Y681438D03*
X620180Y678321D03*
X612811Y688422D03*
X607380Y699671D03*
X617930Y703520D03*
X615510Y692781D03*
X620480Y693827D03*
X609070Y721917D03*
X613730Y717663D03*
X620670Y722216D03*
X606940Y716692D03*
X618270Y713344D03*
X619080Y772610D03*
X619030Y778682D03*
X622030Y786047D03*
X606361Y785390D03*
X612260Y783106D03*
X609347Y778624D03*
X628838Y120216D03*
X628738Y133012D03*
X624800Y184953D03*
Y179953D03*
X623301Y200144D03*
Y194544D03*
X634962Y200121D03*
Y195121D03*
X634212Y281670D03*
X624383Y292591D03*
X631672Y301066D03*
X633773Y310439D03*
X628141Y344818D03*
X634511Y389156D03*
X630691Y405007D03*
Y410007D03*
X636586Y410910D03*
X635840Y449890D03*
X634945Y461888D03*
X628250Y471142D03*
X630420Y491511D03*
X636170Y493028D03*
X622600Y488753D03*
X622199Y506535D03*
X632157Y511230D03*
X625130Y534199D03*
X634530Y521565D03*
X634190Y538267D03*
X636890Y571351D03*
X624870Y573143D03*
X627084Y578257D03*
X634921Y580163D03*
X623940Y628720D03*
X636890Y627095D03*
X629781Y628559D03*
X622510Y635544D03*
X634137Y631342D03*
X627146Y638932D03*
X626340Y668853D03*
X633970Y723033D03*
X628160Y722343D03*
X632530Y716788D03*
X636170Y729335D03*
X632300Y749755D03*
X636910Y745815D03*
X624010Y746351D03*
X629912Y769200D03*
X625010Y778281D03*
X639200Y170100D03*
X639350Y250123D03*
X649995Y296433D03*
X640647Y339854D03*
X639838Y349818D03*
X648425Y373474D03*
X652139Y377125D03*
X641236Y381616D03*
X645236Y377858D03*
X650822Y425295D03*
X647280Y446851D03*
X651080Y455238D03*
X652110Y465238D03*
X646600Y463571D03*
X648956Y469323D03*
X650521Y482930D03*
X647921Y475778D03*
X646105Y492010D03*
X650790Y497730D03*
X646906Y505210D03*
X646460Y512967D03*
X652690Y531693D03*
X645040Y524444D03*
X639673Y576888D03*
X651437Y578943D03*
X653301Y585683D03*
X644636Y627257D03*
X646940Y643448D03*
X641263Y631393D03*
X649173Y629876D03*
X647870Y649784D03*
X646580Y654775D03*
X641630Y668783D03*
X647370Y668643D03*
X643740Y716004D03*
X643970Y722649D03*
X645400Y734600D03*
X650160Y733395D03*
X652660Y749000D03*
X640956Y750643D03*
X646680Y755009D03*
X646500Y746300D03*
X638470Y762212D03*
X647410Y767053D03*
X651690Y778099D03*
X640010Y778215D03*
X644110Y773108D03*
X655947Y53677D03*
X655642Y144915D03*
Y149915D03*
X655695Y159567D03*
Y164567D03*
X655030Y228744D03*
Y223744D03*
X657838Y243407D03*
Y238407D03*
X660899Y311515D03*
X654962Y307698D03*
X668925Y364887D03*
X663632Y366698D03*
X669215Y377488D03*
X655812Y424106D03*
X664450Y435739D03*
X664528Y463432D03*
X660458Y470932D03*
X659828Y465162D03*
X667774Y477992D03*
X661158Y486152D03*
X667070Y483608D03*
X662780Y477039D03*
X660518Y492862D03*
X654240Y511568D03*
X653800Y505331D03*
X659933Y513927D03*
X668573Y514155D03*
X659740Y536019D03*
X667050Y535324D03*
X658980Y610043D03*
X663560Y625019D03*
X654221Y631425D03*
X657550Y655072D03*
X669203Y673040D03*
X653870Y668979D03*
X658220Y671797D03*
X659978Y666274D03*
X657340Y690286D03*
X659300Y734119D03*
X657500Y761500D03*
X656970Y772761D03*
X669987Y53672D03*
X679590Y352829D03*
X677083Y375124D03*
X673368Y416621D03*
X671056Y426300D03*
X673740Y449887D03*
X682764Y444832D03*
X677070Y444820D03*
X679299Y491473D03*
X674156Y503662D03*
X677160Y529422D03*
X675044Y524581D03*
X678386Y668420D03*
X673386D03*
X681480Y777388D03*
X681164Y783461D03*
X669810Y786721D03*
X672500Y779579D03*
X687546Y154228D03*
X689480Y194615D03*
X687869Y386780D03*
X688118Y381043D03*
X685859Y403970D03*
X691037Y401739D03*
X696070Y458901D03*
X700590Y462272D03*
X689017Y497282D03*
X694823Y498932D03*
X689729Y509580D03*
X696891Y507279D03*
X686770Y543325D03*
X691532Y563789D03*
Y575789D03*
Y583789D03*
X685640Y634154D03*
X698386Y667241D03*
X693386D03*
X699600Y776000D03*
X689700Y774500D03*
X711676Y51019D03*
X712239Y452293D03*
X704550Y444407D03*
X704766Y498880D03*
X713978Y498075D03*
X716021Y516945D03*
X700829Y504041D03*
X707920Y505575D03*
X706361Y532632D03*
X716260Y525295D03*
X712740Y593101D03*
X713742Y634373D03*
X708386Y669774D03*
X703386D03*
X713445Y677641D03*
X704000Y770800D03*
X731566Y442136D03*
X726580Y455637D03*
X731570Y464043D03*
X726830Y460815D03*
X727940Y469943D03*
X720140Y478333D03*
X719761Y532432D03*
X727830Y641829D03*
X728690Y649829D03*
X718445Y677641D03*
X736310Y450774D03*
X737350Y464330D03*
X734575Y492575D03*
X745500Y492500D03*
X744020Y566143D03*
X743951Y578833D03*
X744050Y571834D03*
X740430Y616409D03*
X744000Y647919D03*
X733210Y645829D03*
X732540Y653829D03*
X758223Y446532D03*
X748723Y455332D03*
X752960Y653967D03*
X771110Y578643D03*
X770850Y587025D03*
G54D20*
X43898Y168544D03*
Y231457D03*
G54D11*
X-44872Y125213D03*
Y141213D03*
Y232533D03*
D03*
Y248533D03*
D03*
Y738493D03*
Y754493D03*
X-26872Y125213D03*
Y141213D03*
Y232533D03*
D03*
Y248533D03*
D03*
Y738493D03*
Y754493D03*
X556181Y81889D03*
G54D30*
X102362Y247244D03*
Y349606D03*
X354331Y247244D03*
Y349606D03*
G54D21*
X41930Y184229D03*
G54D12*
X-36758Y240533D03*
X-34986D03*
G54D31*
X97627Y426943D03*
X90147D03*
X97627Y435943D03*
X90147D03*
X97627Y444943D03*
X90147D03*
X113858Y453636D03*
X106378D03*
X202207Y222117D03*
X209687D03*
X351910Y331176D03*
X344430D03*
X417881Y412830D03*
X410401D03*
X417881Y420830D03*
X410401D03*
X417881Y428830D03*
X410401D03*
X417881Y436830D03*
X410401D03*
X410551Y452830D03*
X403071D03*
X417881Y444830D03*
X410401D03*
X410551Y460574D03*
X403071D03*
X447841Y424629D03*
Y432798D03*
X455321Y424629D03*
Y432798D03*
X478955Y132391D03*
X486435D03*
G54D22*
X45282Y338300D03*
G54D40*
X197073Y265022D03*
G36*
G01X-39730Y241133D02*
Y238722D01*
G03X-37950Y237433I858J-689D01*
G01X-36794D01*
G03X-34950I922J600D01*
G01X-33794D01*
G03X-32014Y238722I922J600D01*
G01Y241133D01*
X-33614D01*
Y239433D01*
X-38130D01*
Y241133D01*
X-39730D01*
G37*
G54D32*
X118755Y409613D03*
Y417093D03*
X132760Y409149D03*
Y416629D03*
X132135Y497682D03*
Y505162D03*
X140603Y408965D03*
Y416445D03*
X184390Y573395D03*
Y580875D03*
X304851Y323383D03*
Y315903D03*
X501641Y485334D03*
Y492814D03*
X534805Y417861D03*
Y410381D03*
G54D23*
X45554Y488557D03*
X57154D03*
X116984Y461818D03*
X105384D03*
X195789Y450513D03*
X184189D03*
X295177Y595628D03*
X306777D03*
X387677Y591821D03*
X399277D03*
G54D41*
X205940Y690317D03*
Y687758D03*
Y685199D03*
Y682640D03*
Y680081D03*
Y705672D03*
Y703113D03*
Y700554D03*
Y697995D03*
Y695436D03*
Y692876D03*
Y708231D03*
X228940Y680081D03*
Y682640D03*
Y685199D03*
Y687758D03*
Y690317D03*
Y692876D03*
Y695436D03*
Y697995D03*
Y700554D03*
Y703113D03*
Y705672D03*
Y708231D03*
X322468Y644505D03*
Y659860D03*
Y657301D03*
Y654742D03*
Y652182D03*
Y649623D03*
Y647064D03*
Y662419D03*
X322440Y673699D03*
Y671140D03*
Y668581D03*
Y691613D03*
Y689054D03*
Y686495D03*
Y683936D03*
Y681376D03*
Y678817D03*
Y676258D03*
Y696731D03*
Y694172D03*
X345468Y644505D03*
Y647064D03*
Y649623D03*
Y652182D03*
Y654742D03*
Y657301D03*
Y659860D03*
Y662419D03*
X345440Y668581D03*
Y671140D03*
Y673699D03*
Y676258D03*
Y678817D03*
Y681376D03*
Y683936D03*
Y686495D03*
Y689054D03*
Y691613D03*
Y694172D03*
Y696731D03*
X383940Y691317D03*
Y688758D03*
Y686199D03*
Y683640D03*
Y681081D03*
Y706672D03*
Y704113D03*
Y701554D03*
Y698995D03*
Y696436D03*
Y693876D03*
Y709231D03*
X406940Y681081D03*
Y683640D03*
Y686199D03*
Y688758D03*
Y691317D03*
Y693876D03*
Y696436D03*
Y698995D03*
Y701554D03*
Y704113D03*
Y706672D03*
Y709231D03*
X446940Y691258D03*
Y688699D03*
Y686140D03*
Y683581D03*
Y706613D03*
Y704054D03*
Y701495D03*
Y698936D03*
Y696376D03*
Y693817D03*
Y711731D03*
Y709172D03*
X469940Y683581D03*
Y686140D03*
Y688699D03*
Y691258D03*
Y693817D03*
Y696376D03*
Y698936D03*
Y701495D03*
Y704054D03*
Y706613D03*
Y709172D03*
Y711731D03*
X571440Y674199D03*
Y671640D03*
Y669081D03*
Y689554D03*
Y686995D03*
Y684436D03*
Y681876D03*
Y679317D03*
Y676758D03*
Y697231D03*
Y694672D03*
Y692113D03*
X594440Y669081D03*
Y671640D03*
Y674199D03*
Y676758D03*
Y679317D03*
Y681876D03*
Y684436D03*
Y686995D03*
Y689554D03*
Y692113D03*
Y694672D03*
Y697231D03*
X627463Y675600D03*
Y690954D03*
Y688395D03*
Y685836D03*
Y683277D03*
Y680718D03*
Y678159D03*
Y706309D03*
Y703750D03*
Y701191D03*
Y698632D03*
Y696073D03*
Y693514D03*
Y708868D03*
X650463Y675600D03*
Y678159D03*
Y680718D03*
Y683277D03*
Y685836D03*
Y688395D03*
Y690954D03*
Y693514D03*
Y696073D03*
Y698632D03*
Y701191D03*
Y703750D03*
Y706309D03*
Y708868D03*
G54D14*
X10859Y109561D03*
X73740Y20708D03*
X703661D03*
G54D50*
X414961Y98622D03*
G54D51*
X413386Y377165D03*
G54D24*
X49835Y494618D03*
X52985D03*
X65554Y527977D03*
X62404D03*
X105639Y611918D03*
X102489D03*
X105639Y616418D03*
X102489D03*
X105639Y620918D03*
X102489D03*
X105371Y644345D03*
X102221D03*
X105405Y648617D03*
X102255D03*
X126925Y739100D03*
X130075D03*
Y743200D03*
X126925D03*
X139645Y250914D03*
X142795D03*
X139556Y266048D03*
X142706D03*
X139556Y261548D03*
X142706D03*
X139645Y254914D03*
X142795D03*
X146542Y540950D03*
X146642Y537008D03*
X146634Y550353D03*
Y544853D03*
X147735Y581013D03*
Y573105D03*
Y577105D03*
X147688Y594137D03*
X147753Y610702D03*
X147655Y598135D03*
X147753Y619035D03*
Y614735D03*
X152443Y271487D03*
X155593D03*
X152443Y267487D03*
X155593D03*
X149692Y540950D03*
X149792Y537008D03*
X149784Y550353D03*
Y544853D03*
X152234Y555253D03*
X155384D03*
X150885Y581013D03*
Y573105D03*
Y577105D03*
X150838Y594137D03*
X160538Y596933D03*
X157388D03*
X154755Y588235D03*
X157905D03*
X150903Y610702D03*
X150805Y598135D03*
X160538Y610933D03*
X157388D03*
X160505Y605135D03*
X157355D03*
X160538Y600933D03*
X157388D03*
X150903Y619035D03*
Y614735D03*
X160538Y620933D03*
X157388D03*
X160605Y616735D03*
X157455D03*
X165952Y285347D03*
X169102D03*
X165952Y289347D03*
X169102D03*
X180634Y520053D03*
X178396Y524137D03*
X175954Y539647D03*
X172804D03*
X189998Y112977D03*
X193148D03*
X192205Y311603D03*
X189055D03*
X189182Y305819D03*
X192332D03*
X196372Y313617D03*
X196354Y331014D03*
X184634Y505353D03*
X187784D03*
X185134Y511353D03*
X188284D03*
X183784Y520053D03*
X181546Y524137D03*
X185634Y540853D03*
X188784D03*
X190355Y594735D03*
X193505D03*
X190388Y603833D03*
X193538D03*
X190355Y607835D03*
X193505D03*
X190388Y598933D03*
X193538D03*
X190355Y614735D03*
X193505D03*
X190388Y623033D03*
X193538D03*
X190355Y627135D03*
X193505D03*
X188795Y701936D03*
X191945D03*
X193865Y708156D03*
X210998Y114957D03*
X207848D03*
X205708Y277609D03*
X202558D03*
X211872Y284617D03*
X208022D03*
X204872D03*
X199522Y313617D03*
X209165Y300444D03*
X206015D03*
X206680Y320800D03*
X203530D03*
X199504Y331014D03*
X211423Y521467D03*
X197015Y708156D03*
X224740Y84629D03*
X221590D03*
X226847Y216901D03*
Y220901D03*
X221872Y243617D03*
X225022D03*
X225445Y247519D03*
X222295D03*
Y251519D03*
X225445D03*
X224093Y276987D03*
X220943D03*
X217072Y277567D03*
X213922D03*
X215022Y284617D03*
X218175Y297031D03*
X221325D03*
X218150Y293088D03*
X221300D03*
X216022Y313117D03*
X212872D03*
X216022Y309117D03*
X212872D03*
X219572Y319617D03*
X222722D03*
X219572Y315617D03*
X222722D03*
X227872Y316617D03*
X217134Y502853D03*
X220284D03*
X224193Y498103D03*
X227343D03*
X217134Y506853D03*
X220284D03*
X217134Y510853D03*
X220284D03*
X224529Y511865D03*
X227679D03*
X227784Y515853D03*
X224634D03*
X214573Y521467D03*
X219685Y574231D03*
X222835D03*
X219694Y570116D03*
X222844D03*
X229997Y216901D03*
Y220901D03*
X242064Y242228D03*
Y246228D03*
X231022Y316617D03*
X238022Y324117D03*
X234872D03*
X238022Y320117D03*
X234872D03*
X240913Y377150D03*
X241599Y381197D03*
X242993Y511465D03*
X239843D03*
X243018Y515449D03*
X239868D03*
X243230Y527737D03*
X243240Y519714D03*
X243230Y523732D03*
X243280Y531781D03*
X243266Y535789D03*
X242384Y543962D03*
X243420Y539789D03*
X241348Y703150D03*
X258248Y110597D03*
X255098D03*
X245214Y242228D03*
Y246228D03*
X250837Y246929D03*
X253987D03*
X254022Y251117D03*
X250872D03*
X254022Y255117D03*
X250872D03*
X250943Y277987D03*
X254093D03*
X250516Y294009D03*
X247366D03*
X252943Y284402D03*
X256093D03*
X250454Y299348D03*
X247304D03*
X244063Y377150D03*
X244749Y381197D03*
X246380Y527737D03*
X246390Y519714D03*
X246380Y523732D03*
X246430Y531781D03*
X246416Y535789D03*
X245534Y543962D03*
X246570Y539789D03*
X253293Y546912D03*
X256443D03*
X253273Y542889D03*
X256423D03*
X253239Y561853D03*
X250089D03*
X253239Y566153D03*
X250089D03*
X244498Y703150D03*
X263093Y306987D03*
X259943D03*
X275113Y387669D03*
X271363Y529422D03*
X274513D03*
X271134Y522353D03*
X274284D03*
X271363Y533422D03*
X274513D03*
X260320Y547112D03*
X263470D03*
X260334Y543253D03*
X263484D03*
X271398Y541430D03*
X274548D03*
X271363Y537422D03*
X274513D03*
X280067Y247678D03*
X276917D03*
X286563Y250180D03*
X286809Y246800D03*
X288942Y306875D03*
X280494Y330552D03*
X283644D03*
X277821Y349730D03*
X280971D03*
X278263Y387669D03*
X293725Y124910D03*
X296875D03*
X293725Y120910D03*
X296875D03*
X292092Y306875D03*
X300375Y344346D03*
X303525D03*
X306464Y330406D03*
X304970Y334380D03*
X306284Y497853D03*
X303134D03*
X306284Y493853D03*
X303134D03*
X300575Y642208D03*
X303725D03*
Y646192D03*
X300575D03*
X317568Y302798D03*
X314418D03*
X317607Y306876D03*
X314457D03*
X319225Y326386D03*
X316075D03*
X309614Y330406D03*
X308120Y334380D03*
X316331Y378971D03*
X313181D03*
X312675Y639136D03*
X309525D03*
X308785Y651156D03*
X311935D03*
X308785Y659156D03*
X311935D03*
X308785Y655156D03*
X311935D03*
Y647156D03*
X308785D03*
Y675156D03*
X311935D03*
X308785Y663156D03*
X311935D03*
X308785Y671156D03*
X311935D03*
Y667156D03*
X308785D03*
Y683156D03*
X311935D03*
X308785Y687156D03*
X311935D03*
X308785Y691156D03*
X311935D03*
X308785Y679156D03*
X311935D03*
X308785Y699156D03*
X311935D03*
X308785Y695156D03*
X311935D03*
X335798Y117297D03*
X330665Y311864D03*
X327515D03*
X338948Y117297D03*
X351100Y280101D03*
X347950D03*
X351100Y290101D03*
X347950D03*
X351100Y284101D03*
X347950D03*
X351100Y294101D03*
X347950D03*
Y298101D03*
X351100D03*
X344520Y301883D03*
X347670D03*
X351100Y306101D03*
X347950D03*
X350872Y314102D03*
X347722D03*
X347950Y310101D03*
X351100D03*
X351342Y318230D03*
X348192D03*
X361705Y280317D03*
X358555D03*
X361705Y290317D03*
X358555D03*
X361705Y284317D03*
X358555D03*
X361705Y294317D03*
X358555D03*
X361705Y298317D03*
X358555D03*
X359105Y637128D03*
X355955D03*
X359105Y641128D03*
X355955D03*
X359105Y657128D03*
X355955D03*
X359105Y653128D03*
X355955D03*
X359105Y649128D03*
X355955D03*
X359105Y645175D03*
X355955D03*
Y665128D03*
X359105D03*
Y673128D03*
X355955D03*
X359105Y669128D03*
X355955D03*
X359105Y661128D03*
X355955D03*
X359105Y689128D03*
X355955D03*
X359105Y685128D03*
X355955D03*
X359105Y681128D03*
X355955D03*
X359105Y677128D03*
X355955D03*
X359105Y701128D03*
X355955D03*
X359105Y697128D03*
X355955D03*
X359105Y693128D03*
X355955D03*
X357096Y723537D03*
X360246D03*
X369428Y727622D03*
X369336Y735459D03*
X357096Y735537D03*
X360246D03*
X369336Y731459D03*
X357096Y727537D03*
X360246D03*
Y739537D03*
X357096D03*
X369336Y743459D03*
Y739459D03*
X360246Y743537D03*
X357096D03*
X378508Y117817D03*
X375358D03*
X373433Y685656D03*
X370283D03*
Y681656D03*
X373433D03*
Y677656D03*
X370283D03*
X373485Y715026D03*
X376635D03*
X384333Y715248D03*
X372578Y727622D03*
X372486Y735459D03*
Y731459D03*
Y743459D03*
Y739459D03*
X398016Y676213D03*
X394866D03*
X399443Y716254D03*
X387483Y715248D03*
X412631Y264679D03*
X409481D03*
Y260489D03*
X412631D03*
Y256489D03*
X409481D03*
Y252489D03*
X412631D03*
Y272731D03*
X409481D03*
Y268679D03*
X412631D03*
X405343Y676183D03*
X402193D03*
X402593Y716254D03*
X418063Y681569D03*
X421213D03*
X418852Y685654D03*
X422002D03*
X433265Y687156D03*
X436415D03*
Y679156D03*
X433265D03*
Y683156D03*
X436415D03*
X433265Y691156D03*
X436415D03*
X433265Y707156D03*
X436415D03*
X433265Y703156D03*
X436415D03*
X433265Y699156D03*
X436415D03*
X433265Y695156D03*
X436415D03*
X433265Y711156D03*
X436415D03*
X433265Y715156D03*
X436415D03*
X434280Y719128D03*
X437430D03*
X454371Y638786D03*
X451221D03*
X451226Y642685D03*
X454376D03*
X453233Y657403D03*
X450083D03*
X477640Y139364D03*
Y143364D03*
Y147364D03*
Y151364D03*
X479125Y172113D03*
Y164113D03*
Y168113D03*
X478535Y180383D03*
X475385D03*
X479125Y176113D03*
X476385Y556648D03*
X479535D03*
X476385Y560648D03*
X479535D03*
X476385Y566694D03*
X479535D03*
X476385Y570694D03*
X479535D03*
X476366Y656713D03*
X473216D03*
X473363Y663623D03*
X476513D03*
X482126Y126402D03*
X485276D03*
X480790Y139364D03*
X492699Y128666D03*
X480790Y143364D03*
Y147364D03*
Y151364D03*
X482275Y172113D03*
Y164113D03*
Y168113D03*
X494644Y157761D03*
Y162261D03*
X482275Y176113D03*
X493963Y563025D03*
X494063Y567825D03*
Y571725D03*
Y579525D03*
Y575625D03*
X485465Y678656D03*
X488615D03*
X485465Y682656D03*
X488615D03*
Y686656D03*
X485465D03*
X488615Y690656D03*
X485465D03*
X488615Y694656D03*
X485465D03*
X488615Y698656D03*
X485465D03*
X508274Y137686D03*
X505124D03*
X495849Y128666D03*
X508274Y150686D03*
X505124D03*
Y146686D03*
X508274D03*
Y142186D03*
X505124D03*
X497794Y157761D03*
Y162261D03*
X504550Y201800D03*
X507700D03*
X508663Y463223D03*
Y468723D03*
X497113Y563025D03*
X497213Y567825D03*
Y571725D03*
Y579525D03*
Y575625D03*
X509917Y655007D03*
X508578Y666397D03*
X509884Y670488D03*
X511293Y674660D03*
X508143D03*
X509823Y679002D03*
X512465Y120512D03*
X515615D03*
X515438Y137692D03*
X512288D03*
X515401Y153797D03*
X518551D03*
X515458Y142189D03*
X512308D03*
X515375Y159940D03*
X518525D03*
X516875Y182600D03*
X513725D03*
X511813Y463223D03*
Y468723D03*
X521963Y543025D03*
X525113D03*
X512263Y594625D03*
X515413D03*
X524399Y645214D03*
X513067Y655007D03*
X511728Y666397D03*
X513034Y670488D03*
X512973Y679002D03*
X533846Y135146D03*
X530696D03*
X541614Y135415D03*
Y139415D03*
X533846Y139146D03*
X530696D03*
X541614Y151415D03*
X530696Y151146D03*
X533846D03*
X541614Y155415D03*
X530696Y155146D03*
X533846D03*
X541614Y147415D03*
X533846Y143146D03*
X530696D03*
Y147146D03*
X533846D03*
X541614Y143415D03*
X530559Y167329D03*
X533709D03*
X541614Y163415D03*
X530696Y163146D03*
X533846D03*
X541614Y159415D03*
X541675Y216100D03*
X538525D03*
X535763Y452423D03*
X538913D03*
X535363Y470423D03*
X538513D03*
X535763Y460123D03*
X538913D03*
X531527Y483627D03*
X534677D03*
X541622Y644931D03*
X527549Y645214D03*
X541882Y650277D03*
X544764Y135415D03*
Y139415D03*
Y151415D03*
Y155415D03*
Y147415D03*
Y143415D03*
X556699Y149274D03*
X544764Y163415D03*
X551604Y162541D03*
X554754D03*
X544764Y159415D03*
X555863Y183023D03*
X555706Y239501D03*
X552556D03*
X555749Y243395D03*
X552599D03*
X555749Y247595D03*
X552599D03*
X555749Y258095D03*
X552599D03*
X557613Y544225D03*
X554463D03*
X557713Y548125D03*
X554563D03*
X557613Y540325D03*
X554463D03*
X548493Y643163D03*
X551643D03*
X544772Y644931D03*
X545032Y650277D03*
X557765Y669156D03*
Y673156D03*
Y665156D03*
Y677156D03*
Y689156D03*
Y685156D03*
Y681156D03*
Y693156D03*
Y701156D03*
Y697156D03*
X572083Y136404D03*
X568933D03*
X572083Y140404D03*
X568933D03*
X572083Y144404D03*
X568933D03*
X572083Y148404D03*
X568933D03*
X572083Y152404D03*
X568933D03*
X572083Y156404D03*
X568933D03*
X559849Y149274D03*
X568933Y160404D03*
X572083D03*
X559013Y183023D03*
X559333Y643123D03*
X562483D03*
X560915Y669156D03*
Y673156D03*
Y665156D03*
Y677156D03*
Y689156D03*
Y685156D03*
Y681156D03*
Y693156D03*
Y701156D03*
Y697156D03*
X586999Y240895D03*
X590149D03*
X578366Y278093D03*
X581516D03*
Y282093D03*
X578366D03*
Y286093D03*
X581516D03*
X578366Y290093D03*
X581516D03*
Y294093D03*
X578366D03*
X587420Y663828D03*
X590570D03*
X604965Y675156D03*
Y679156D03*
Y683156D03*
Y687156D03*
Y691156D03*
Y695156D03*
X619012Y589645D03*
X615862D03*
X619045Y585543D03*
X615895D03*
X619045Y597943D03*
X615895D03*
X619012Y608845D03*
X615862D03*
X619045Y617943D03*
X615895D03*
X619012Y613745D03*
X615862D03*
X608115Y675156D03*
Y679156D03*
Y683156D03*
Y687156D03*
Y691156D03*
X613086Y697395D03*
X616236D03*
X608115Y695156D03*
X630716Y195307D03*
X627566D03*
X630716Y199307D03*
X627566D03*
X640663Y387285D03*
X643813D03*
X640663Y392085D03*
X643813D03*
X640663Y396985D03*
X643813D03*
Y401583D03*
X640663D03*
Y405883D03*
X643813D03*
X648862Y591745D03*
X652012D03*
X648795Y595943D03*
X651945D03*
X648862Y611745D03*
X652012D03*
X648895Y607543D03*
X652045D03*
X648862Y601745D03*
X652012D03*
X651495Y624443D03*
X648862Y615745D03*
X652012D03*
X651227Y720674D03*
X648077D03*
Y716674D03*
X651227D03*
X649027Y728674D03*
X652177D03*
X648077Y724674D03*
X651227D03*
X661545Y596443D03*
X658395D03*
X661545Y592143D03*
X658395D03*
X661647Y601976D03*
X658497D03*
X664307Y609468D03*
X667457D03*
X661712Y618541D03*
X658562D03*
X654645Y624443D03*
X661745Y614543D03*
X658595D03*
X660889Y676595D03*
X664039D03*
X672363Y388185D03*
X675513D03*
Y392385D03*
X672363D03*
X675513Y401785D03*
X672363D03*
Y406785D03*
X675513D03*
Y397585D03*
X672363D03*
G54D42*
X227718Y280988D03*
X230718D03*
X266418Y583783D03*
X277590Y579734D03*
G54D60*
X546181Y81889D03*
G54D33*
X151969Y98622D03*
G54D15*
X20859Y109561D03*
X83740Y20708D03*
X78740Y30708D03*
X507489Y360278D03*
X713661Y20708D03*
X708661Y30708D03*
G54D70*
G01X5906Y278740D02*
X25591D01*
G02X31496Y272835I0J-5905D01*
G01Y127165D01*
G02X25591Y121260I-5905J0D01*
G01X5906D01*
G03X0Y115354I0J-5906D01*
G01Y7874D01*
G03X7874Y0I7874J0D01*
G01X779528D01*
G03X787402Y7874I0J7874D01*
G01Y120669D01*
G03X781496Y126575I-5906J0D01*
G01X780315D01*
G02X774409Y132480I0J5906D01*
G01Y286024D01*
G02X780315Y291929I5906J-1D01*
G01X781496D01*
G03X787402Y297835I0J5906D01*
G01Y664173D01*
G03X779528Y672047I-7874J0D01*
G01X746693D01*
G02X738819Y679921I0J7874D01*
G01Y819708D01*
X738695Y819832D01*
X736866Y821652D01*
G01X5906Y278740D02*
G02X0Y284646I0J5906D01*
G01Y664173D01*
G02X7874Y672047I7874J0D01*
G01X40787D01*
G03X48661Y679921I0J7874D01*
G01Y819674D01*
X49201Y820214D01*
X50646Y821652D01*
G01X327026D02*
X50646D01*
G01X89851Y96614D02*
G03X107000I8574J-10787D01*
G01X89851Y710787D02*
G03X107000I8574J-10787D01*
G01X105512Y105512D02*
G03X91339I-7086J0D01*
G01X89852Y96614D02*
G03X91339Y99696I-2450J3082D01*
G01Y105512D02*
Y99696D01*
G01X105512Y719685D02*
G03X91339I-7086J0D01*
G01X89852Y710787D02*
G03X91339Y713869I-2450J3082D01*
G01Y719685D02*
Y713869D01*
G01X105512Y99696D02*
G03X107000Y96614I3937J1D01*
G01X105512Y99696D02*
Y105512D01*
G01Y713869D02*
G03X107000Y710787I3937J1D01*
G01X105512Y713869D02*
Y719685D01*
G01X327026Y821652D02*
X328915Y819773D01*
X328976Y819712D01*
Y792323D01*
G03X336457I3740J0D01*
G01Y819673D01*
X336476Y819692D01*
X338446Y821652D01*
G01X378606D02*
X338446D01*
G01X378606D02*
X380551Y819707D01*
Y741142D01*
G03X406929I13189J0D01*
G01Y819675D01*
X406946Y819692D01*
X408916Y821652D01*
G01X685296D02*
X408916D01*
G01X680097Y96167D02*
G03X697856I8880J-10537D01*
G01X680097Y96166D02*
G03X681497Y99177I-2537J3011D01*
G01X696457Y105315D02*
G03X681497I-7480J0D01*
G01D02*
Y99177D01*
G01X680097Y710340D02*
G03X697856I8880J-10537D01*
G01X696457Y719488D02*
G03X681497I-7480J0D01*
G01X680097Y710340D02*
G03X681497Y713350I-2537J3011D01*
G01Y719488D02*
Y713350D01*
G01X696457Y99177D02*
G03X697857Y96166I3937J0D01*
G01X696457Y99177D02*
Y105315D01*
G01Y713350D02*
G03X697857Y710340I3937J1D01*
G01X696457Y713350D02*
Y719488D01*
G01X696716Y821652D02*
X694746Y819692D01*
X694724Y819670D01*
Y792323D01*
G02X687244I-3740J0D01*
G01Y819710D01*
X686388Y820566D01*
X685296Y821652D01*
G01X736866D02*
X696716D01*
G54D16*
X25439Y303260D03*
Y356804D03*
G54D34*
X144058Y370080D03*
Y373230D03*
X148058D03*
Y370080D03*
X147999Y380582D03*
Y383732D03*
X146675Y413599D03*
Y410449D03*
X145531Y526980D03*
Y523830D03*
X152058Y370080D03*
Y373230D03*
X160058Y370080D03*
Y373230D03*
X156058D03*
Y370080D03*
X164058Y373230D03*
Y370080D03*
X156104Y380583D03*
Y383733D03*
X163735Y380294D03*
Y383444D03*
X150709Y506778D03*
Y509928D03*
X149482Y526928D03*
Y523778D03*
X163330Y593010D03*
Y589860D03*
X164163Y625058D03*
Y628208D03*
X179627Y236399D03*
Y239549D03*
X175627Y236399D03*
Y239549D03*
X176058Y370080D03*
Y373230D03*
X168058Y370080D03*
Y373230D03*
X180058D03*
Y370080D03*
X172058Y373230D03*
Y370080D03*
X179801Y380622D03*
Y383772D03*
X171934Y380727D03*
Y383877D03*
X169330Y593010D03*
Y589860D03*
X176263Y593108D03*
Y589958D03*
X176830Y625060D03*
Y628210D03*
X172530Y625060D03*
Y628210D03*
X168430Y624960D03*
Y628110D03*
X179693Y726467D03*
Y729617D03*
X190058Y349894D03*
Y346744D03*
X194185Y349984D03*
Y346834D03*
X184058Y370080D03*
Y373230D03*
X188058D03*
Y370080D03*
X187970Y380726D03*
Y383876D03*
X188886Y553920D03*
Y550770D03*
X183330Y593210D03*
Y590060D03*
X182430Y625260D03*
Y628410D03*
X189940Y714931D03*
Y718081D03*
X185440Y714931D03*
Y718081D03*
X194440Y714898D03*
Y718048D03*
Y739081D03*
Y727581D03*
Y730731D03*
X185440Y727581D03*
Y730731D03*
X189940Y727581D03*
Y730731D03*
Y739081D03*
X185440D03*
X194440Y742231D03*
X189940D03*
X185440D03*
X198653Y281646D03*
X209447Y296692D03*
Y293542D03*
X197847Y297731D03*
X198653Y284796D03*
X209018Y304542D03*
Y307692D03*
X203447Y304742D03*
Y307892D03*
X199447Y304742D03*
Y307892D03*
X197847Y300881D03*
X203520Y327969D03*
Y324819D03*
X196887Y326622D03*
Y323472D03*
X208687Y382271D03*
Y379121D03*
X200687D03*
Y382271D03*
X204687D03*
Y379121D03*
X208209Y486428D03*
Y483278D03*
X207940Y714931D03*
Y718081D03*
X203440Y714898D03*
Y718048D03*
X198940Y714931D03*
Y718081D03*
X207940Y739081D03*
X203440D03*
X198940D03*
X207940Y727581D03*
Y730731D03*
X203440Y727581D03*
Y730731D03*
X198940Y727581D03*
Y730731D03*
X207940Y742231D03*
X203440D03*
X198940D03*
X221421Y233971D03*
Y237121D03*
X217564Y246804D03*
Y249954D03*
X213265Y268130D03*
Y271280D03*
X226995Y269007D03*
Y272157D03*
X222018Y280912D03*
X227718Y277838D03*
X222018Y284062D03*
X215518Y302042D03*
Y305192D03*
X227947Y309542D03*
Y312692D03*
X227712Y302770D03*
Y299620D03*
X212447Y327042D03*
X220447Y323542D03*
Y326692D03*
X212447Y330192D03*
X227767Y336322D03*
Y333172D03*
X220687Y382271D03*
Y379121D03*
X216687Y382271D03*
Y379121D03*
X212687D03*
Y382271D03*
X224687D03*
Y379121D03*
X212709Y486428D03*
Y483278D03*
X216709Y486428D03*
Y483278D03*
X218867Y521088D03*
Y524238D03*
X225940Y727581D03*
Y730731D03*
X212440Y739081D03*
X221440D03*
X216940Y730731D03*
Y727581D03*
X225940Y739081D03*
X216940D03*
X212440Y730731D03*
Y727581D03*
X221440Y730731D03*
Y727581D03*
X212440Y742231D03*
X221440D03*
X225940D03*
X216940D03*
X228745Y265718D03*
Y262568D03*
X237910Y277692D03*
Y274542D03*
X241525Y278042D03*
Y281192D03*
X234060Y274542D03*
Y277692D03*
X230718Y277838D03*
X234789Y286926D03*
Y283776D03*
X235107Y297434D03*
X234789Y290675D03*
Y293825D03*
X228408Y291228D03*
Y294378D03*
X228439Y287413D03*
Y284263D03*
X235018Y313042D03*
X240307Y312400D03*
X231600Y303157D03*
Y306307D03*
X235107Y300584D03*
X235018Y316192D03*
X240307Y315550D03*
X235518Y329412D03*
X243612Y336435D03*
Y333285D03*
X235518Y332562D03*
X238643Y360796D03*
Y363946D03*
X236687Y379121D03*
Y382271D03*
X232687Y377621D03*
Y380771D03*
X235319Y470268D03*
Y467118D03*
X241979Y466578D03*
Y469728D03*
X241909Y478128D03*
Y474978D03*
X228689Y494181D03*
Y491031D03*
X240509Y578028D03*
Y574878D03*
X236209Y578028D03*
Y574878D03*
X231809Y578028D03*
Y574878D03*
X239440Y739081D03*
X230440D03*
X234940Y727581D03*
Y730731D03*
X239440D03*
Y727581D03*
X230440Y730731D03*
Y727581D03*
X234940Y739081D03*
X239440Y742231D03*
X230440D03*
X234940D03*
X258263Y245896D03*
Y249046D03*
X252399Y262158D03*
Y265308D03*
X244634Y266202D03*
Y263052D03*
X246947Y278042D03*
Y281192D03*
X248625Y274017D03*
Y270867D03*
X244480Y273876D03*
Y270726D03*
X252261Y272285D03*
Y269135D03*
X256097Y292632D03*
Y289482D03*
X247018Y284912D03*
Y288062D03*
X248250Y310104D03*
Y313254D03*
X252250Y310104D03*
Y313254D03*
X244359Y312651D03*
X256218Y318562D03*
Y315412D03*
X251231Y321857D03*
Y325007D03*
X244359Y315801D03*
X248690Y388933D03*
Y392083D03*
X248687Y379121D03*
Y382271D03*
X252687Y379121D03*
Y382271D03*
X258687Y388902D03*
Y392052D03*
X256687Y379121D03*
Y382271D03*
X251309Y466078D03*
Y469228D03*
X255509Y465978D03*
Y469128D03*
X251309Y478128D03*
Y474978D03*
X255509Y478128D03*
Y474978D03*
X246089Y478179D03*
Y475029D03*
X255048Y516344D03*
X250209Y516778D03*
X259000Y516356D03*
X258748Y509415D03*
Y512565D03*
X255048Y519494D03*
X250209Y519928D03*
X259000Y519506D03*
X249368Y543928D03*
Y547078D03*
X251809Y555928D03*
Y552778D03*
X246209Y553728D03*
Y550578D03*
X248440Y739081D03*
X243940Y727581D03*
Y730731D03*
X257440Y739081D03*
X252940D03*
X257440Y730731D03*
Y727581D03*
X243940Y739081D03*
X252940Y730731D03*
Y727581D03*
X248440Y730731D03*
Y727581D03*
Y742231D03*
X257440D03*
X252940D03*
X243940D03*
X271339Y84895D03*
Y81745D03*
X269625Y100289D03*
Y103439D03*
X264953Y114152D03*
Y117302D03*
X272953Y114152D03*
Y117302D03*
X268953Y114152D03*
Y117302D03*
X262132Y245889D03*
Y249039D03*
X260143Y275621D03*
Y272471D03*
X272218Y318562D03*
Y315412D03*
X264218Y318562D03*
Y315412D03*
X260218Y318562D03*
Y315412D03*
X268218Y318562D03*
Y315412D03*
X260350Y366987D03*
Y363837D03*
X272687Y379121D03*
Y382271D03*
X268687D03*
Y379121D03*
X260687Y382271D03*
Y379121D03*
X260609Y465978D03*
Y469128D03*
X264909Y465978D03*
Y469128D03*
X269209Y465978D03*
Y469128D03*
X273509Y465978D03*
Y469128D03*
X260609Y478128D03*
Y474978D03*
X269109Y478128D03*
Y474978D03*
X264909Y478128D03*
Y474978D03*
X273209Y478128D03*
Y474978D03*
X270209Y490278D03*
Y493428D03*
X274209Y490278D03*
Y493428D03*
X270209Y518428D03*
Y515278D03*
X274209Y518428D03*
Y515278D03*
X267242Y543505D03*
Y546655D03*
X266418Y580633D03*
X270940Y730731D03*
Y727581D03*
X261940Y739081D03*
X266440D03*
X261940Y730731D03*
Y727581D03*
X270940Y739081D03*
X266440Y730731D03*
Y727581D03*
X261940Y742231D03*
X266440D03*
X270940D03*
X279552Y84908D03*
Y81758D03*
X287905Y84695D03*
Y81545D03*
X283786Y84695D03*
Y81545D03*
X275542Y84928D03*
Y81778D03*
X284199Y106109D03*
Y109259D03*
X276953Y117302D03*
Y114152D03*
X276218Y318562D03*
Y315412D03*
X284218Y318562D03*
Y315412D03*
X280218Y318562D03*
Y315412D03*
X288218Y318562D03*
Y315412D03*
X283498Y367402D03*
Y364252D03*
X276825Y367017D03*
Y363867D03*
X282368Y478188D03*
Y475038D03*
X278311Y478202D03*
Y475052D03*
X278209Y517928D03*
Y514778D03*
X277590Y582884D03*
X288630Y727362D03*
Y730512D03*
X283440Y739081D03*
X275440D03*
X279940Y727281D03*
Y730431D03*
X287440Y739081D03*
X279440D03*
X275440Y730731D03*
Y727581D03*
X283440Y742231D03*
X275440D03*
X287440D03*
X279440D03*
X295862Y84735D03*
Y81585D03*
X291824Y84815D03*
Y81665D03*
X299135Y322650D03*
Y325800D03*
X292218Y318562D03*
Y315412D03*
X296218Y318562D03*
Y315412D03*
X297131Y369021D03*
Y372171D03*
X301131Y369021D03*
Y372171D03*
X305708Y507818D03*
Y510968D03*
X296913Y510981D03*
Y507831D03*
X301457Y507829D03*
Y510979D03*
X294909Y586128D03*
Y582978D03*
X292420Y652392D03*
Y649242D03*
X296453Y649199D03*
Y652349D03*
X299638Y707048D03*
X303538D03*
X299638Y710198D03*
X303538D03*
X299440Y739081D03*
X291440D03*
X292840Y729522D03*
Y732672D03*
X303440Y739081D03*
X301450Y729345D03*
Y726195D03*
X295440Y739081D03*
X305640Y730942D03*
Y727792D03*
X299440Y742231D03*
X291440D03*
X303440D03*
X295440D03*
X310939Y84815D03*
Y81665D03*
X319005Y84635D03*
Y81485D03*
X314926Y84714D03*
Y81564D03*
X313789Y115659D03*
Y118809D03*
X313190Y342353D03*
Y339203D03*
X321987Y536052D03*
Y539202D03*
X311940Y739081D03*
X307940D03*
X313410Y732276D03*
Y729126D03*
X309530Y730942D03*
Y727792D03*
X311940Y742231D03*
X307940D03*
X327005Y84635D03*
Y81485D03*
X323005Y84635D03*
Y81485D03*
X368920Y716909D03*
Y720059D03*
X364920Y716909D03*
Y720059D03*
X383860Y658089D03*
Y661239D03*
X389999Y665278D03*
Y668428D03*
X407506Y653413D03*
Y650263D03*
X413940Y739081D03*
Y730731D03*
Y727581D03*
Y742231D03*
X427079Y522404D03*
Y519254D03*
X420289Y697510D03*
Y700660D03*
X422940Y727581D03*
Y730731D03*
X426940Y739081D03*
X427440Y727581D03*
Y730731D03*
X418440Y739081D03*
X422940D03*
X431440D03*
X418440Y730731D03*
Y727581D03*
X426940Y742231D03*
X418440D03*
X422940D03*
X431440D03*
X435773Y265453D03*
Y262303D03*
X445440Y727581D03*
Y730731D03*
X435940Y739081D03*
X436440Y727581D03*
Y730731D03*
X444940Y739081D03*
X440440D03*
X440940Y730731D03*
Y727581D03*
X435940Y742231D03*
X444940D03*
X440440D03*
X459000Y202925D03*
Y206075D03*
X450957Y486305D03*
Y489455D03*
X458938Y655198D03*
Y652048D03*
X453235Y647580D03*
Y650730D03*
X449183Y647604D03*
Y650754D03*
X462440Y739081D03*
X453940D03*
X454440Y727581D03*
Y730731D03*
X458440D03*
Y727581D03*
X462440Y730731D03*
Y727581D03*
X458440Y739081D03*
X449940Y730731D03*
Y727581D03*
X449440Y739081D03*
X462440Y742231D03*
X453940D03*
X458440D03*
X449440D03*
X469000Y139925D03*
Y143075D03*
X478000Y210075D03*
Y206925D03*
X473898Y649648D03*
Y652798D03*
X466440Y739081D03*
X470440D03*
Y730731D03*
Y727581D03*
X466440Y730731D03*
Y727581D03*
Y742231D03*
X470440D03*
X495738Y543850D03*
Y547000D03*
X502000Y232425D03*
X506000D03*
X510000D03*
X502000Y235575D03*
X506000D03*
X510000D03*
X498563Y460516D03*
Y457366D03*
X501938Y534030D03*
X506938Y539940D03*
Y536790D03*
X510938Y539940D03*
Y536790D03*
X501938Y537180D03*
X496338Y555750D03*
Y558900D03*
X503628Y571790D03*
Y568640D03*
X507528Y571790D03*
Y568640D03*
X505138Y597300D03*
Y594150D03*
X521320Y170525D03*
X525400Y186475D03*
Y183325D03*
X521400Y186475D03*
Y183325D03*
X521320Y173675D03*
X514059Y230075D03*
Y226925D03*
X517577Y450051D03*
Y446901D03*
X522638Y450298D03*
Y447148D03*
X526638Y533350D03*
X518838D03*
X514938D03*
X522738D03*
X526638Y536500D03*
X518838D03*
X514938D03*
X522738D03*
X519638Y597200D03*
Y594050D03*
X523538Y597300D03*
Y594150D03*
X512533Y626791D03*
Y629941D03*
X514940Y726581D03*
Y729731D03*
X519440Y738081D03*
X523940Y726581D03*
Y729731D03*
X519440D03*
Y726581D03*
X514940Y738081D03*
X523940D03*
X519440Y741231D03*
X514940D03*
X523940D03*
X533768Y186419D03*
Y183269D03*
X537928Y186433D03*
Y183283D03*
X529272Y186459D03*
Y183309D03*
X542002Y186426D03*
Y183276D03*
X531238Y450298D03*
Y447148D03*
X528338Y474348D03*
Y477498D03*
X530538Y533350D03*
X541538Y533250D03*
X534438Y533350D03*
X530538Y536500D03*
X541538Y536400D03*
X534438Y536500D03*
X536438Y597200D03*
Y594050D03*
X531438Y597300D03*
Y594150D03*
X527438Y597300D03*
Y594150D03*
X540338Y597200D03*
Y594050D03*
X537440Y738081D03*
X541940D03*
X532940Y726581D03*
Y729731D03*
X528440Y738081D03*
X541940Y729731D03*
Y726581D03*
X532940Y738081D03*
X537440Y729731D03*
Y726581D03*
X528440Y729731D03*
Y726581D03*
X537440Y741231D03*
X541940D03*
X528440D03*
X532940D03*
X546000Y186426D03*
Y183276D03*
X557174Y269020D03*
Y272170D03*
X545438Y533250D03*
Y536400D03*
X548238Y547950D03*
X555138Y561450D03*
Y564600D03*
X548238Y551100D03*
X555138Y568350D03*
Y571500D03*
X544238Y597200D03*
Y594050D03*
X555138Y587400D03*
Y584250D03*
X548138Y597200D03*
Y594050D03*
X555508Y642118D03*
Y645268D03*
X550940Y738081D03*
X546440D03*
X555440Y738381D03*
X546440Y729731D03*
Y726581D03*
X555440Y729731D03*
Y726581D03*
X550940Y729731D03*
Y726581D03*
Y741231D03*
X546440D03*
X555440Y741531D03*
X563474Y234520D03*
X569874D03*
X563474Y237670D03*
X569874D03*
X566774Y269020D03*
Y272170D03*
X570874Y269020D03*
Y272170D03*
X568940Y726581D03*
Y729731D03*
X564440Y738581D03*
X573440D03*
X559940Y726581D03*
Y729731D03*
X568940Y738581D03*
X573440Y729731D03*
Y726581D03*
X564440Y729731D03*
Y726581D03*
X559940Y738581D03*
X564440Y741731D03*
X573440D03*
X568940D03*
X559940D03*
X576074Y234520D03*
Y237670D03*
X583651Y705451D03*
Y702301D03*
X588151Y705451D03*
Y702301D03*
X579151Y705451D03*
Y702301D03*
X577940Y726581D03*
Y729731D03*
X587940Y738081D03*
Y729731D03*
Y726581D03*
X577940Y738581D03*
X587940Y741231D03*
X577940Y741731D03*
X596741Y242818D03*
Y245968D03*
X604741Y242818D03*
Y245968D03*
X600741D03*
Y242818D03*
X596741Y254218D03*
Y257368D03*
X596641Y266268D03*
Y263118D03*
X604741Y254218D03*
Y257368D03*
X600741D03*
Y254218D03*
X604641Y266268D03*
Y263118D03*
X600641D03*
Y266268D03*
X601440Y738081D03*
X605940D03*
X596940D03*
X592440Y726581D03*
Y729731D03*
Y738081D03*
X596940Y729731D03*
Y726581D03*
X601440Y729731D03*
Y726581D03*
X605940Y729731D03*
Y726581D03*
X601440Y741231D03*
X605940D03*
X596940D03*
X592440D03*
X608741Y242818D03*
Y245968D03*
X612841D03*
Y242818D03*
X608741Y254218D03*
Y257368D03*
X608641Y266268D03*
Y263118D03*
X612774Y263120D03*
Y266270D03*
X612841Y257368D03*
Y254218D03*
X609345Y669937D03*
Y666787D03*
X617235Y682716D03*
Y685866D03*
X619440Y738081D03*
X614940D03*
X610440D03*
X619440Y729731D03*
Y726581D03*
X614940Y729731D03*
Y726581D03*
X610440Y729731D03*
Y726581D03*
X619440Y741231D03*
X614940D03*
X610440D03*
X626970Y587418D03*
Y584268D03*
X632570Y587618D03*
Y584468D03*
X636870Y587618D03*
Y584468D03*
X626070Y619468D03*
Y622618D03*
X633137Y619570D03*
Y622720D03*
X623957Y718092D03*
Y714942D03*
X627957Y718092D03*
Y714942D03*
X623940Y726581D03*
Y729731D03*
Y738081D03*
X628440D03*
X636440D03*
X632440D03*
X628440Y729722D03*
Y726572D03*
X623940Y741231D03*
X628440D03*
X636440D03*
X632440D03*
X648838Y414360D03*
Y411210D03*
X645237Y587620D03*
Y584470D03*
X640970Y587718D03*
Y584568D03*
X646070Y619668D03*
Y622818D03*
X640070Y619668D03*
Y622818D03*
X650339Y660418D03*
X645752Y660431D03*
X650339Y663568D03*
X645752Y663581D03*
X648000Y738925D03*
X652660Y739360D03*
Y742510D03*
X648000Y742075D03*
X668422Y373085D03*
Y369935D03*
X659938Y383660D03*
Y380510D03*
X663938D03*
Y383660D03*
X658338Y414360D03*
Y411210D03*
X653538Y411310D03*
Y414460D03*
X663238D03*
Y411310D03*
X667538Y414360D03*
Y411210D03*
X664503Y672129D03*
Y668979D03*
X661034Y683798D03*
Y680648D03*
X656660Y739360D03*
Y742510D03*
X672522Y369935D03*
Y373085D03*
X683468Y625772D03*
Y628922D03*
X687468Y625772D03*
Y628922D03*
X711261Y625723D03*
Y628873D03*
X715761Y625723D03*
Y628873D03*
X709500Y740425D03*
Y743575D03*
X720261Y625723D03*
Y628873D03*
X729500Y734575D03*
Y731425D03*
Y740425D03*
Y743575D03*
G54D52*
X434102Y232640D03*
Y311875D03*
X583913Y69167D03*
X608571D03*
G54D61*
X590999D03*
Y77041D03*
Y84915D03*
X615657Y69167D03*
Y77041D03*
Y84915D03*
G54D25*
X51240Y807872D03*
X55177D03*
X59114D03*
X63051D03*
X66988D03*
X70925D03*
X74862D03*
X78799D03*
X82736D03*
X86673D03*
X90610D03*
X94547D03*
X98484D03*
X102421D03*
X106358D03*
X110295D03*
X114232D03*
X118169D03*
X122106D03*
X126043D03*
X129980D03*
X133917D03*
X137854D03*
X141791D03*
X145728D03*
X149665D03*
X153602D03*
X157539D03*
X161476D03*
X165413D03*
X169350D03*
X173287D03*
X177224D03*
X181161D03*
X185098D03*
X189035D03*
X192972D03*
X196909D03*
X200846D03*
X204783D03*
X208720D03*
X212658D03*
X216594D03*
X220532D03*
X224469D03*
X228406D03*
X232343D03*
X236280D03*
X240217D03*
X244154D03*
X248091D03*
X252028D03*
X255965D03*
X259902D03*
X263839D03*
X267776D03*
X271713D03*
X275650D03*
X279587D03*
X283524D03*
X287461D03*
X291398D03*
X295335D03*
X299272D03*
X303209D03*
X307146D03*
X311083D03*
X315020D03*
X318957D03*
X322894D03*
X326831D03*
X338642D03*
X342579D03*
X346516D03*
X350453D03*
X354390D03*
X358327D03*
X362264D03*
X366201D03*
X370138D03*
X374075D03*
X409510D03*
X413447D03*
X417384D03*
X421321D03*
X425258D03*
X429195D03*
X433132D03*
X437069D03*
X441006D03*
X444943D03*
X448880D03*
X452817D03*
X456754D03*
X460691D03*
X464628D03*
X468565D03*
X472502D03*
X476439D03*
X480376D03*
X484313D03*
X488250D03*
X492187D03*
X496124D03*
X500061D03*
X503998D03*
X507935D03*
X511872D03*
X515809D03*
X519746D03*
X523683D03*
X527620D03*
X531557D03*
X535494D03*
X539431D03*
X543368D03*
X547305D03*
X551242D03*
X555179D03*
X559116D03*
X563053D03*
X566990D03*
X570928D03*
X574864D03*
X578802D03*
X582739D03*
X586676D03*
X590613D03*
X594550D03*
X598487D03*
X602424D03*
X606361D03*
X610298D03*
X614235D03*
X618172D03*
X622109D03*
X626046D03*
X629983D03*
X633920D03*
X637857D03*
X641794D03*
X645731D03*
X649668D03*
X653605D03*
X657542D03*
X661479D03*
X665416D03*
X669353D03*
X673290D03*
X677227D03*
X681164D03*
X685101D03*
X696912D03*
X700849D03*
X704786D03*
X708723D03*
X712660D03*
X716597D03*
X720534D03*
X724471D03*
X728408D03*
X732345D03*
G54D43*
X228130Y225834D03*
X236593Y258887D03*
X244122Y250972D03*
G54D71*
G01X38493Y-241864D02*
Y-246864D01*
G01X37036Y-241864D02*
X39950D01*
G01X44860Y-246864D02*
X42326D01*
Y-241864D01*
X44860D01*
G01X43846Y-244281D02*
X42326D01*
G01X47426Y-241864D02*
Y-246864D01*
X49960D01*
G01X53793Y-247031D02*
X53666Y-246947D01*
Y-246781D01*
X53793Y-246697D01*
X53920Y-246781D01*
Y-246947D01*
X53793Y-247031D01*
G01Y-244781D02*
X53666Y-244697D01*
Y-244531D01*
X53793Y-244447D01*
X53920Y-244531D01*
Y-244697D01*
X53793Y-244781D01*
G01X58576Y-248531D02*
X57943Y-247697D01*
X57626Y-246864D01*
Y-243531D01*
X57943Y-242697D01*
X58576Y-241864D01*
G01X63993D02*
X63486Y-242031D01*
X63106Y-242447D01*
X62853Y-242947D01*
X62663Y-243614D01*
X62600Y-244364D01*
X62663Y-245114D01*
X62853Y-245781D01*
X63106Y-246281D01*
X63486Y-246697D01*
X63993Y-246864D01*
X64500Y-246697D01*
X64880Y-246281D01*
X65133Y-245781D01*
X65323Y-245114D01*
X65386Y-244364D01*
X65323Y-243614D01*
X65133Y-242947D01*
X64880Y-242447D01*
X64500Y-242031D01*
X63993Y-241864D01*
G01X67700Y-245864D02*
X68080Y-246447D01*
X68586Y-246781D01*
X69156Y-246864D01*
X69663Y-246781D01*
X70170Y-246364D01*
X70486Y-245864D01*
X70550Y-245364D01*
X70423Y-244781D01*
X69980Y-244364D01*
X69536Y-244197D01*
X68966D01*
G01X69536D02*
X69916Y-243947D01*
X70233Y-243531D01*
X70360Y-243031D01*
X70233Y-242531D01*
X69916Y-242114D01*
X69346Y-241864D01*
X68776Y-241947D01*
X68206Y-242281D01*
G01X74510Y-248531D02*
X75143Y-247697D01*
X75460Y-246864D01*
Y-243531D01*
X75143Y-242697D01*
X74510Y-241864D01*
G01X77900Y-245864D02*
X78280Y-246447D01*
X78786Y-246781D01*
X79356Y-246864D01*
X79863Y-246781D01*
X80370Y-246364D01*
X80686Y-245864D01*
X80750Y-245364D01*
X80623Y-244781D01*
X80180Y-244364D01*
X79736Y-244197D01*
X79166D01*
G01X79736D02*
X80116Y-243947D01*
X80433Y-243531D01*
X80560Y-243031D01*
X80433Y-242531D01*
X80116Y-242114D01*
X79546Y-241864D01*
X78976Y-241947D01*
X78406Y-242281D01*
G01X83190Y-242697D02*
X83570Y-242197D01*
X84013Y-241947D01*
X84520Y-241864D01*
X85153Y-242031D01*
X85596Y-242447D01*
X85723Y-242947D01*
X85660Y-243447D01*
X85406Y-243864D01*
X84140Y-244697D01*
X83570Y-245281D01*
X83190Y-246114D01*
X83063Y-246864D01*
X85723D01*
G01X89366D02*
X89493Y-245781D01*
X89683Y-244864D01*
X89936Y-244031D01*
X90253Y-243114D01*
X90760Y-241864D01*
X88226D01*
G01X93770Y-245197D02*
X95416D01*
G01X98490Y-242697D02*
X98870Y-242197D01*
X99313Y-241947D01*
X99820Y-241864D01*
X100453Y-242031D01*
X100896Y-242447D01*
X101023Y-242947D01*
X100960Y-243447D01*
X100706Y-243864D01*
X99440Y-244697D01*
X98870Y-245281D01*
X98490Y-246114D01*
X98363Y-246864D01*
X101023D01*
G01X103400Y-245864D02*
X103780Y-246447D01*
X104286Y-246781D01*
X104856Y-246864D01*
X105363Y-246781D01*
X105870Y-246364D01*
X106186Y-245864D01*
X106250Y-245364D01*
X106123Y-244781D01*
X105680Y-244364D01*
X105236Y-244197D01*
X104666D01*
G01X105236D02*
X105616Y-243947D01*
X105933Y-243531D01*
X106060Y-243031D01*
X105933Y-242531D01*
X105616Y-242114D01*
X105046Y-241864D01*
X104476Y-241947D01*
X103906Y-242281D01*
G01X110653Y-246864D02*
Y-241864D01*
X108310Y-245447D01*
X111476D01*
G01X113600Y-246114D02*
X113980Y-246531D01*
X114423Y-246781D01*
X114993Y-246864D01*
X115563Y-246697D01*
X116006Y-246364D01*
X116323Y-245781D01*
X116386Y-245114D01*
X116260Y-244447D01*
X115943Y-244031D01*
X115500Y-243697D01*
X115056Y-243614D01*
X114613Y-243697D01*
X114043Y-244031D01*
X114233Y-241864D01*
X115943D01*
G01X123990Y-246864D02*
Y-241864D01*
X126396D01*
G01X125510Y-244281D02*
X123990D01*
G01X128710Y-246864D02*
X130293Y-241864D01*
X131876Y-246864D01*
G01X131306Y-245114D02*
X129280D01*
G01X134063Y-246864D02*
X136723Y-241864D01*
G01X134063D02*
X136723Y-246864D01*
G01X140493Y-247031D02*
X140366Y-246947D01*
Y-246781D01*
X140493Y-246697D01*
X140620Y-246781D01*
Y-246947D01*
X140493Y-247031D01*
G01Y-244781D02*
X140366Y-244697D01*
Y-244531D01*
X140493Y-244447D01*
X140620Y-244531D01*
Y-244697D01*
X140493Y-244781D01*
G01X145276Y-248531D02*
X144643Y-247697D01*
X144326Y-246864D01*
Y-243531D01*
X144643Y-242697D01*
X145276Y-241864D01*
G01X150693D02*
X150186Y-242031D01*
X149806Y-242447D01*
X149553Y-242947D01*
X149363Y-243614D01*
X149300Y-244364D01*
X149363Y-245114D01*
X149553Y-245781D01*
X149806Y-246281D01*
X150186Y-246697D01*
X150693Y-246864D01*
X151200Y-246697D01*
X151580Y-246281D01*
X151833Y-245781D01*
X152023Y-245114D01*
X152086Y-244364D01*
X152023Y-243614D01*
X151833Y-242947D01*
X151580Y-242447D01*
X151200Y-242031D01*
X150693Y-241864D01*
G01X154400Y-245864D02*
X154780Y-246447D01*
X155286Y-246781D01*
X155856Y-246864D01*
X156363Y-246781D01*
X156870Y-246364D01*
X157186Y-245864D01*
X157250Y-245364D01*
X157123Y-244781D01*
X156680Y-244364D01*
X156236Y-244197D01*
X155666D01*
G01X156236D02*
X156616Y-243947D01*
X156933Y-243531D01*
X157060Y-243031D01*
X156933Y-242531D01*
X156616Y-242114D01*
X156046Y-241864D01*
X155476Y-241947D01*
X154906Y-242281D01*
G01X161210Y-248531D02*
X161843Y-247697D01*
X162160Y-246864D01*
Y-243531D01*
X161843Y-242697D01*
X161210Y-241864D01*
G01X164600Y-245864D02*
X164980Y-246447D01*
X165486Y-246781D01*
X166056Y-246864D01*
X166563Y-246781D01*
X167070Y-246364D01*
X167386Y-245864D01*
X167450Y-245364D01*
X167323Y-244781D01*
X166880Y-244364D01*
X166436Y-244197D01*
X165866D01*
G01X166436D02*
X166816Y-243947D01*
X167133Y-243531D01*
X167260Y-243031D01*
X167133Y-242531D01*
X166816Y-242114D01*
X166246Y-241864D01*
X165676Y-241947D01*
X165106Y-242281D01*
G01X170016Y-246281D02*
X170460Y-246697D01*
X170966Y-246864D01*
X171473Y-246697D01*
X171916Y-246197D01*
X172233Y-245447D01*
X172360Y-244697D01*
Y-243781D01*
X172233Y-243031D01*
X171916Y-242364D01*
X171536Y-242031D01*
X171093Y-241864D01*
X170586Y-242031D01*
X170206Y-242364D01*
X169953Y-242864D01*
X169826Y-243531D01*
X169953Y-244114D01*
X170270Y-244697D01*
X170650Y-245031D01*
X171093Y-245114D01*
X171600Y-244947D01*
X171980Y-244531D01*
X172360Y-243781D01*
G01X176066Y-246864D02*
X176193Y-245781D01*
X176383Y-244864D01*
X176636Y-244031D01*
X176953Y-243114D01*
X177460Y-241864D01*
X174926D01*
G01X180470Y-245197D02*
X182116D01*
G01X185000Y-245864D02*
X185380Y-246447D01*
X185886Y-246781D01*
X186456Y-246864D01*
X186963Y-246781D01*
X187470Y-246364D01*
X187786Y-245864D01*
X187850Y-245364D01*
X187723Y-244781D01*
X187280Y-244364D01*
X186836Y-244197D01*
X186266D01*
G01X186836D02*
X187216Y-243947D01*
X187533Y-243531D01*
X187660Y-243031D01*
X187533Y-242531D01*
X187216Y-242114D01*
X186646Y-241864D01*
X186076Y-241947D01*
X185506Y-242281D01*
G01X190290Y-244781D02*
X190733Y-244197D01*
X191113Y-243864D01*
X191620Y-243697D01*
X192063Y-243864D01*
X192380Y-244197D01*
X192633Y-244697D01*
X192696Y-245281D01*
X192633Y-245781D01*
X192380Y-246281D01*
X192000Y-246697D01*
X191556Y-246864D01*
X191050Y-246697D01*
X190606Y-246197D01*
X190353Y-245447D01*
X190290Y-244614D01*
X190416Y-243531D01*
X190606Y-242947D01*
X190923Y-242364D01*
X191366Y-241947D01*
X191810Y-241864D01*
X192253Y-242031D01*
X192570Y-242447D01*
G01X196593Y-246864D02*
Y-241864D01*
X195833Y-242864D01*
G01Y-246864D02*
X197353D01*
G01X202453D02*
Y-241864D01*
X200110Y-245447D01*
X203276D01*
G01X26493Y-176864D02*
Y-251864D01*
X526493D01*
Y-176864D01*
X26493D01*
G01X221493D02*
Y-251864D01*
G01Y-226864D02*
X324493D01*
Y-201864D01*
G01X221493D02*
X324493D01*
G01X332000Y-236864D02*
Y-231864D01*
X333266D01*
X333773Y-232114D01*
X334153Y-232447D01*
X334470Y-232947D01*
X334723Y-233531D01*
X334786Y-234364D01*
X334723Y-235197D01*
X334470Y-235781D01*
X334153Y-236281D01*
X333773Y-236614D01*
X333266Y-236864D01*
X332000D01*
G01X336910D02*
X338493Y-231864D01*
X340076Y-236864D01*
G01X339506Y-235114D02*
X337480D01*
G01X343593Y-231864D02*
Y-236864D01*
G01X342136Y-231864D02*
X345050D01*
G01X349960Y-236864D02*
X347426D01*
Y-231864D01*
X349960D01*
G01X348946Y-234281D02*
X347426D01*
G01X353793Y-237031D02*
X353666Y-236947D01*
Y-236781D01*
X353793Y-236697D01*
X353920Y-236781D01*
Y-236947D01*
X353793Y-237031D01*
G01Y-234781D02*
X353666Y-234697D01*
Y-234531D01*
X353793Y-234447D01*
X353920Y-234531D01*
Y-234697D01*
X353793Y-234781D01*
G01X326493Y-176864D02*
Y-251864D01*
G01X324493Y-176864D02*
Y-251864D01*
G01X326493Y-226864D02*
X526493D01*
G01X332126Y-211864D02*
Y-206864D01*
X333646D01*
X334153Y-207114D01*
X334533Y-207697D01*
X334660Y-208364D01*
X334533Y-209031D01*
X334216Y-209531D01*
X333646Y-209781D01*
X332126D01*
G01X337353Y-212031D02*
X339633Y-206864D01*
G01X342136Y-211864D02*
Y-206864D01*
X345050Y-211864D01*
Y-206864D01*
G01X348693Y-212031D02*
X348566Y-211947D01*
Y-211781D01*
X348693Y-211697D01*
X348820Y-211781D01*
Y-211947D01*
X348693Y-212031D01*
G01Y-209781D02*
X348566Y-209697D01*
Y-209531D01*
X348693Y-209447D01*
X348820Y-209531D01*
Y-209697D01*
X348693Y-209781D01*
G01X326493Y-201864D02*
X526493D01*
G01X332126Y-186864D02*
Y-181864D01*
X333646D01*
X334153Y-182114D01*
X334533Y-182697D01*
X334660Y-183364D01*
X334533Y-184031D01*
X334216Y-184531D01*
X333646Y-184781D01*
X332126D01*
G01X337226Y-186864D02*
Y-181864D01*
X338810D01*
X339316Y-182114D01*
X339633Y-182447D01*
X339760Y-183114D01*
X339633Y-183781D01*
X339253Y-184197D01*
X338810Y-184447D01*
X337226D01*
G01X338810D02*
X339760Y-186864D01*
G01X343593D02*
X343086Y-186781D01*
X342643Y-186447D01*
X342263Y-185947D01*
X342010Y-185364D01*
X341883Y-184697D01*
Y-184031D01*
X342010Y-183364D01*
X342263Y-182781D01*
X342643Y-182281D01*
X343086Y-181947D01*
X343593Y-181864D01*
X344100Y-181947D01*
X344543Y-182281D01*
X344923Y-182781D01*
X345176Y-183364D01*
X345303Y-184031D01*
Y-184697D01*
X345176Y-185364D01*
X344923Y-185947D01*
X344543Y-186447D01*
X344100Y-186781D01*
X343593Y-186864D01*
G01X347426Y-185864D02*
X347743Y-186364D01*
X348123Y-186697D01*
X348566Y-186864D01*
X349073Y-186697D01*
X349453Y-186364D01*
X349833Y-185864D01*
X349960Y-185197D01*
Y-181864D01*
G01X355060Y-186864D02*
X352526D01*
Y-181864D01*
X355060D01*
G01X354046Y-184281D02*
X352526D01*
G01X360286Y-182281D02*
X359906Y-182031D01*
X359463Y-181864D01*
X358956D01*
X358386Y-182114D01*
X357943Y-182531D01*
X357626Y-183031D01*
X357373Y-183864D01*
X357310Y-184614D01*
X357436Y-185364D01*
X357626Y-185864D01*
X358006Y-186364D01*
X358450Y-186697D01*
X358893Y-186864D01*
X359336D01*
X359780Y-186697D01*
X360160Y-186447D01*
X360476Y-186114D01*
G01X363993Y-181864D02*
Y-186864D01*
G01X362536Y-181864D02*
X365450D01*
G01X369093Y-187031D02*
X368966Y-186947D01*
Y-186781D01*
X369093Y-186697D01*
X369220Y-186781D01*
Y-186947D01*
X369093Y-187031D01*
G01Y-184781D02*
X368966Y-184697D01*
Y-184531D01*
X369093Y-184447D01*
X369220Y-184531D01*
Y-184697D01*
X369093Y-184781D01*
G01X447126Y-236864D02*
Y-231864D01*
X448710D01*
X449216Y-232114D01*
X449533Y-232447D01*
X449660Y-233114D01*
X449533Y-233781D01*
X449153Y-234197D01*
X448710Y-234447D01*
X447126D01*
G01X448710D02*
X449660Y-236864D01*
G01X454760D02*
X452226D01*
Y-231864D01*
X454760D01*
G01X453746Y-234281D02*
X452226D01*
G01X457010Y-231864D02*
X458593Y-236864D01*
X460176Y-231864D01*
G01X463693Y-237031D02*
X463566Y-236947D01*
Y-236781D01*
X463693Y-236697D01*
X463820Y-236781D01*
Y-236947D01*
X463693Y-237031D01*
G01Y-234781D02*
X463566Y-234697D01*
Y-234531D01*
X463693Y-234447D01*
X463820Y-234531D01*
Y-234697D01*
X463693Y-234781D01*
G01X441493Y-226864D02*
Y-251864D01*
G01X490493Y-226864D02*
Y-251864D01*
G01X-1043962Y-705877D02*
Y2342823D01*
X2300638D01*
Y-705877D01*
X-1043962D01*
G01X37198Y-238524D02*
X37825Y-239049D01*
X38530Y-239364D01*
X39156D01*
X39783Y-239049D01*
X40253Y-238524D01*
X40488Y-237789D01*
X40331Y-237054D01*
X39940Y-236424D01*
X39235Y-236004D01*
X38295Y-235794D01*
X37746Y-235374D01*
X37511Y-234639D01*
X37668Y-233904D01*
X38060Y-233379D01*
X38608Y-233064D01*
X39156D01*
X39705Y-233274D01*
X40175Y-233799D01*
G01X43498Y-239364D02*
Y-233064D01*
G01X46788D02*
Y-239364D01*
G01Y-236214D02*
X43498D01*
G01X50503Y-233064D02*
X52383D01*
G01X51443D02*
Y-239364D01*
G01X50503D02*
X52383D01*
G01X59310D02*
X56176D01*
Y-233064D01*
X59310D01*
G01X58056Y-236109D02*
X56176D01*
G01X62241Y-239364D02*
Y-233064D01*
X65845Y-239364D01*
Y-233064D01*
G01X70186Y-240519D02*
X70500Y-239154D01*
G01X76643Y-233064D02*
Y-239364D01*
G01X74841Y-233064D02*
X78445D01*
G01X80985Y-239364D02*
X82943Y-233064D01*
X84901Y-239364D01*
G01X84196Y-237159D02*
X81690D01*
G01X88303Y-233064D02*
X90183D01*
G01X89243D02*
Y-239364D01*
G01X88303D02*
X90183D01*
G01X93193Y-233064D02*
X94290Y-239364D01*
X95543Y-233064D01*
X96796Y-239364D01*
X97893Y-233064D01*
G01X99885Y-239364D02*
X101843Y-233064D01*
X103801Y-239364D01*
G01X103096Y-237159D02*
X100590D01*
G01X106341Y-239364D02*
Y-233064D01*
X109945Y-239364D01*
Y-233064D01*
G01X119176Y-239364D02*
Y-233064D01*
X121135D01*
X121761Y-233379D01*
X122153Y-233799D01*
X122310Y-234639D01*
X122153Y-235479D01*
X121683Y-236004D01*
X121135Y-236319D01*
X119176D01*
G01X121135D02*
X122310Y-239364D01*
G01X127043Y-239574D02*
X126886Y-239469D01*
Y-239259D01*
X127043Y-239154D01*
X127200Y-239259D01*
Y-239469D01*
X127043Y-239574D01*
G01X133343Y-239364D02*
X132716Y-239259D01*
X132168Y-238839D01*
X131698Y-238209D01*
X131385Y-237474D01*
X131228Y-236634D01*
Y-235794D01*
X131385Y-234954D01*
X131698Y-234219D01*
X132168Y-233589D01*
X132716Y-233169D01*
X133343Y-233064D01*
X133970Y-233169D01*
X134518Y-233589D01*
X134988Y-234219D01*
X135301Y-234954D01*
X135458Y-235794D01*
Y-236634D01*
X135301Y-237474D01*
X134988Y-238209D01*
X134518Y-238839D01*
X133970Y-239259D01*
X133343Y-239364D01*
G01X139643Y-239574D02*
X139486Y-239469D01*
Y-239259D01*
X139643Y-239154D01*
X139800Y-239259D01*
Y-239469D01*
X139643Y-239574D01*
G01X147666Y-233589D02*
X147196Y-233274D01*
X146648Y-233064D01*
X146021D01*
X145316Y-233379D01*
X144768Y-233904D01*
X144376Y-234534D01*
X144063Y-235584D01*
X143985Y-236529D01*
X144141Y-237474D01*
X144376Y-238104D01*
X144846Y-238734D01*
X145395Y-239154D01*
X145943Y-239364D01*
X146491D01*
X147040Y-239154D01*
X147510Y-238839D01*
X147901Y-238419D01*
G01X152243Y-239574D02*
X152086Y-239469D01*
Y-239259D01*
X152243Y-239154D01*
X152400Y-239259D01*
Y-239469D01*
X152243Y-239574D01*
G01X37120Y-229364D02*
Y-223064D01*
G01X40096D02*
X37120Y-226949D01*
G01X40566Y-229364D02*
X38451Y-225164D01*
G01X43420Y-223064D02*
Y-227579D01*
X43733Y-228524D01*
X44360Y-229154D01*
X45143Y-229364D01*
X45926Y-229154D01*
X46553Y-228524D01*
X46866Y-227579D01*
Y-223064D01*
G01X53010Y-229364D02*
X49876D01*
Y-223064D01*
X53010D01*
G01X51756Y-226109D02*
X49876D01*
G01X56803Y-223064D02*
X58683D01*
G01X57743D02*
Y-229364D01*
G01X56803D02*
X58683D01*
G01X68698Y-228524D02*
X69325Y-229049D01*
X70030Y-229364D01*
X70656D01*
X71283Y-229049D01*
X71753Y-228524D01*
X71988Y-227789D01*
X71831Y-227054D01*
X71440Y-226424D01*
X70735Y-226004D01*
X69795Y-225794D01*
X69246Y-225374D01*
X69011Y-224639D01*
X69168Y-223904D01*
X69560Y-223379D01*
X70108Y-223064D01*
X70656D01*
X71205Y-223274D01*
X71675Y-223799D01*
G01X74998Y-229364D02*
Y-223064D01*
G01X78288D02*
Y-229364D01*
G01Y-226214D02*
X74998D01*
G01X80985Y-229364D02*
X82943Y-223064D01*
X84901Y-229364D01*
G01X84196Y-227159D02*
X81690D01*
G01X87441Y-229364D02*
Y-223064D01*
X91045Y-229364D01*
Y-223064D01*
G01X100198Y-229364D02*
Y-223064D01*
G01X103488D02*
Y-229364D01*
G01Y-226214D02*
X100198D01*
G01X106498Y-228524D02*
X107125Y-229049D01*
X107830Y-229364D01*
X108456D01*
X109083Y-229049D01*
X109553Y-228524D01*
X109788Y-227789D01*
X109631Y-227054D01*
X109240Y-226424D01*
X108535Y-226004D01*
X107595Y-225794D01*
X107046Y-225374D01*
X106811Y-224639D01*
X106968Y-223904D01*
X107360Y-223379D01*
X107908Y-223064D01*
X108456D01*
X109005Y-223274D01*
X109475Y-223799D01*
G01X113503Y-223064D02*
X115383D01*
G01X114443D02*
Y-229364D01*
G01X113503D02*
X115383D01*
G01X118785D02*
X120743Y-223064D01*
X122701Y-229364D01*
G01X121996Y-227159D02*
X119490D01*
G01X125241Y-229364D02*
Y-223064D01*
X128845Y-229364D01*
Y-223064D01*
G01X133813Y-226214D02*
X135380D01*
Y-228104D01*
X134910Y-228734D01*
X134361Y-229154D01*
X133578Y-229364D01*
X132795Y-229154D01*
X132246Y-228734D01*
X131776Y-228104D01*
X131463Y-227369D01*
X131306Y-226529D01*
Y-225794D01*
X131463Y-225164D01*
X131776Y-224429D01*
X132246Y-223799D01*
X132716Y-223379D01*
X133343Y-223064D01*
X133891D01*
X134518Y-223274D01*
X134988Y-223694D01*
G01X139486Y-230519D02*
X139800Y-229154D01*
G01X145943Y-223064D02*
Y-229364D01*
G01X144141Y-223064D02*
X147745D01*
G01X150285Y-229364D02*
X152243Y-223064D01*
X154201Y-229364D01*
G01X153496Y-227159D02*
X150990D01*
G01X158543Y-229364D02*
X157916Y-229259D01*
X157368Y-228839D01*
X156898Y-228209D01*
X156585Y-227474D01*
X156428Y-226634D01*
Y-225794D01*
X156585Y-224954D01*
X156898Y-224219D01*
X157368Y-223589D01*
X157916Y-223169D01*
X158543Y-223064D01*
X159170Y-223169D01*
X159718Y-223589D01*
X160188Y-224219D01*
X160501Y-224954D01*
X160658Y-225794D01*
Y-226634D01*
X160501Y-227474D01*
X160188Y-228209D01*
X159718Y-228839D01*
X159170Y-229259D01*
X158543Y-229364D01*
G01X171143D02*
Y-226529D01*
X169576Y-223064D01*
G01X172710D02*
X171143Y-226529D01*
G01X175720Y-223064D02*
Y-227579D01*
X176033Y-228524D01*
X176660Y-229154D01*
X177443Y-229364D01*
X178226Y-229154D01*
X178853Y-228524D01*
X179166Y-227579D01*
Y-223064D01*
G01X181785Y-229364D02*
X183743Y-223064D01*
X185701Y-229364D01*
G01X184996Y-227159D02*
X182490D01*
G01X188241Y-229364D02*
Y-223064D01*
X191845Y-229364D01*
Y-223064D01*
G01X37041Y-219364D02*
Y-213064D01*
X40645Y-219364D01*
Y-213064D01*
G01X45143Y-219364D02*
X44516Y-219259D01*
X43968Y-218839D01*
X43498Y-218209D01*
X43185Y-217474D01*
X43028Y-216634D01*
Y-215794D01*
X43185Y-214954D01*
X43498Y-214219D01*
X43968Y-213589D01*
X44516Y-213169D01*
X45143Y-213064D01*
X45770Y-213169D01*
X46318Y-213589D01*
X46788Y-214219D01*
X47101Y-214954D01*
X47258Y-215794D01*
Y-216634D01*
X47101Y-217474D01*
X46788Y-218209D01*
X46318Y-218839D01*
X45770Y-219259D01*
X45143Y-219364D01*
G01X51443Y-219574D02*
X51286Y-219469D01*
Y-219259D01*
X51443Y-219154D01*
X51600Y-219259D01*
Y-219469D01*
X51443Y-219574D01*
G01X57743Y-219364D02*
Y-213064D01*
X56803Y-214324D01*
G01Y-219364D02*
X58683D01*
G01X64043D02*
X64591Y-219259D01*
X65218Y-218944D01*
X65610Y-218419D01*
X65766Y-217684D01*
X65610Y-216949D01*
X65140Y-216319D01*
X64435Y-216004D01*
X63651D01*
X63181Y-215794D01*
X62790Y-215269D01*
X62633Y-214534D01*
X62868Y-213799D01*
X63416Y-213274D01*
X64043Y-213064D01*
X64670Y-213274D01*
X65218Y-213799D01*
X65453Y-214534D01*
X65296Y-215269D01*
X64905Y-215794D01*
X64435Y-216004D01*
X63651D01*
X62946Y-216319D01*
X62476Y-216949D01*
X62320Y-217684D01*
X62476Y-218419D01*
X62868Y-218944D01*
X63495Y-219259D01*
X64043Y-219364D01*
G01X70343D02*
X70891Y-219259D01*
X71518Y-218944D01*
X71910Y-218419D01*
X72066Y-217684D01*
X71910Y-216949D01*
X71440Y-216319D01*
X70735Y-216004D01*
X69951D01*
X69481Y-215794D01*
X69090Y-215269D01*
X68933Y-214534D01*
X69168Y-213799D01*
X69716Y-213274D01*
X70343Y-213064D01*
X70970Y-213274D01*
X71518Y-213799D01*
X71753Y-214534D01*
X71596Y-215269D01*
X71205Y-215794D01*
X70735Y-216004D01*
X69951D01*
X69246Y-216319D01*
X68776Y-216949D01*
X68620Y-217684D01*
X68776Y-218419D01*
X69168Y-218944D01*
X69795Y-219259D01*
X70343Y-219364D01*
G01X76486Y-220519D02*
X76800Y-219154D01*
G01X80593Y-213064D02*
X81690Y-219364D01*
X82943Y-213064D01*
X84196Y-219364D01*
X85293Y-213064D01*
G01X90810Y-219364D02*
X87676D01*
Y-213064D01*
X90810D01*
G01X89556Y-216109D02*
X87676D01*
G01X93741Y-219364D02*
Y-213064D01*
X97345Y-219364D01*
Y-213064D01*
G01X106498Y-219364D02*
Y-213064D01*
G01X109788D02*
Y-219364D01*
G01Y-216214D02*
X106498D01*
G01X112093Y-213064D02*
X113190Y-219364D01*
X114443Y-213064D01*
X115696Y-219364D01*
X116793Y-213064D01*
G01X118785Y-219364D02*
X120743Y-213064D01*
X122701Y-219364D01*
G01X121996Y-217159D02*
X119490D01*
G01X131855Y-214114D02*
X132325Y-213484D01*
X132873Y-213169D01*
X133500Y-213064D01*
X134283Y-213274D01*
X134831Y-213799D01*
X134988Y-214429D01*
X134910Y-215059D01*
X134596Y-215584D01*
X133030Y-216634D01*
X132325Y-217369D01*
X131855Y-218419D01*
X131698Y-219364D01*
X134988D01*
G01X137841D02*
Y-213064D01*
X141445Y-219364D01*
Y-213064D01*
G01X144220Y-219364D02*
Y-213064D01*
X145786D01*
X146413Y-213379D01*
X146883Y-213799D01*
X147275Y-214429D01*
X147588Y-215164D01*
X147666Y-216214D01*
X147588Y-217264D01*
X147275Y-217999D01*
X146883Y-218629D01*
X146413Y-219049D01*
X145786Y-219364D01*
X144220D01*
G01X156976D02*
Y-213064D01*
X158935D01*
X159561Y-213379D01*
X159953Y-213799D01*
X160110Y-214639D01*
X159953Y-215479D01*
X159483Y-216004D01*
X158935Y-216319D01*
X156976D01*
G01X158935D02*
X160110Y-219364D01*
G01X163120D02*
Y-213064D01*
X164686D01*
X165313Y-213379D01*
X165783Y-213799D01*
X166175Y-214429D01*
X166488Y-215164D01*
X166566Y-216214D01*
X166488Y-217264D01*
X166175Y-217999D01*
X165783Y-218629D01*
X165313Y-219049D01*
X164686Y-219364D01*
X163120D01*
G01X171143Y-219574D02*
X170986Y-219469D01*
Y-219259D01*
X171143Y-219154D01*
X171300Y-219259D01*
Y-219469D01*
X171143Y-219574D01*
G01X61143Y-206664D02*
X58623Y-206247D01*
X56418Y-204581D01*
X54528Y-202081D01*
X53268Y-199164D01*
X52638Y-195831D01*
Y-192497D01*
X53268Y-189164D01*
X54528Y-186247D01*
X56418Y-183748D01*
X58623Y-182081D01*
X61143Y-181664D01*
X63663Y-182081D01*
X65868Y-183748D01*
X67758Y-186247D01*
X69018Y-189164D01*
X69648Y-192497D01*
Y-195831D01*
X69018Y-199164D01*
X67758Y-202081D01*
X65868Y-204581D01*
X63663Y-206247D01*
X61143Y-206664D01*
G01X63663Y-199997D02*
X67443Y-206664D01*
G01X80988Y-189998D02*
Y-201664D01*
X82248Y-204581D01*
X84138Y-206247D01*
X86343Y-206664D01*
X88548Y-206247D01*
X90438Y-204581D01*
X91698Y-201664D01*
G01Y-206664D02*
Y-189998D01*
G01X117213Y-206664D02*
Y-189998D01*
G01Y-192914D02*
X115953Y-191248D01*
X114063Y-190414D01*
X111858Y-189998D01*
X109653Y-190831D01*
X107763Y-192497D01*
X106503Y-194998D01*
X105873Y-198331D01*
X106503Y-201664D01*
X107763Y-204165D01*
X109653Y-205831D01*
X111858Y-206664D01*
X114063Y-206247D01*
X115953Y-204998D01*
X117213Y-203331D01*
G01X131388Y-206664D02*
Y-189998D01*
G01Y-194164D02*
X132648Y-192081D01*
X134538Y-190414D01*
X137058Y-189998D01*
X139263Y-190414D01*
X141153Y-192081D01*
X142098Y-194998D01*
Y-206664D01*
G01X161943Y-181664D02*
Y-206664D01*
G01X157533Y-189998D02*
X166353D01*
G01X192813Y-206664D02*
Y-189998D01*
G01Y-192914D02*
X191553Y-191248D01*
X189663Y-190414D01*
X187458Y-189998D01*
X185253Y-190831D01*
X183363Y-192497D01*
X182103Y-194998D01*
X181473Y-198331D01*
X182103Y-201664D01*
X183363Y-204165D01*
X185253Y-205831D01*
X187458Y-206664D01*
X189663Y-206247D01*
X191553Y-204998D01*
X192813Y-203331D01*
G01X232493Y-186364D02*
Y-194364D01*
X236493D01*
G01X244293D02*
Y-189031D01*
G01Y-189964D02*
X243893Y-189431D01*
X243293Y-189164D01*
X242593Y-189031D01*
X241893Y-189297D01*
X241293Y-189831D01*
X240893Y-190631D01*
X240693Y-191697D01*
X240893Y-192764D01*
X241293Y-193564D01*
X241893Y-194097D01*
X242593Y-194364D01*
X243293Y-194231D01*
X243893Y-193831D01*
X244293Y-193298D01*
G01X248393Y-196764D02*
X248993Y-197031D01*
X249793Y-196764D01*
X250293Y-196231D01*
X250693Y-195564D01*
X251293Y-193431D01*
X252593Y-189031D01*
G01X249393D02*
X251293Y-193431D01*
G01X256993Y-190764D02*
X260193D01*
X259893Y-189831D01*
X259393Y-189297D01*
X258693Y-189031D01*
X257993Y-189164D01*
X257393Y-189564D01*
X256993Y-190497D01*
X256793Y-191298D01*
Y-192097D01*
X256993Y-192897D01*
X257493Y-193697D01*
X258093Y-194231D01*
X258793Y-194364D01*
X259493Y-194097D01*
X260193Y-193298D01*
G01X265093Y-194364D02*
Y-189031D01*
G01Y-190097D02*
X265593Y-189564D01*
X266093Y-189164D01*
X266793Y-189031D01*
X267293Y-189164D01*
X267893Y-189564D01*
G01X254793Y-236364D02*
X257193D01*
G01X255993D02*
Y-244364D01*
G01X254793D02*
X257193D01*
G01X262593D02*
Y-239031D01*
G01Y-240097D02*
X263093Y-239564D01*
X263593Y-239164D01*
X264293Y-239031D01*
X264793Y-239164D01*
X265393Y-239564D01*
G01X270493Y-240764D02*
X273693D01*
X273393Y-239831D01*
X272893Y-239297D01*
X272193Y-239031D01*
X271493Y-239164D01*
X270893Y-239564D01*
X270493Y-240497D01*
X270293Y-241298D01*
Y-242097D01*
X270493Y-242897D01*
X270993Y-243697D01*
X271593Y-244231D01*
X272293Y-244364D01*
X272993Y-244097D01*
X273693Y-243298D01*
G01X278293Y-244364D02*
Y-239031D01*
G01Y-240364D02*
X278693Y-239697D01*
X279293Y-239164D01*
X280093Y-239031D01*
X280793Y-239164D01*
X281393Y-239697D01*
X281693Y-240631D01*
Y-244364D01*
G01X286493Y-240764D02*
X289693D01*
X289393Y-239831D01*
X288893Y-239297D01*
X288193Y-239031D01*
X287493Y-239164D01*
X286893Y-239564D01*
X286493Y-240497D01*
X286293Y-241298D01*
Y-242097D01*
X286493Y-242897D01*
X286993Y-243697D01*
X287593Y-244231D01*
X288293Y-244364D01*
X288993Y-244097D01*
X289693Y-243298D01*
G01X245893Y-219364D02*
Y-211364D01*
X248493Y-218031D01*
X251093Y-211364D01*
Y-219364D01*
G01X253993D02*
X256493Y-211364D01*
X258993Y-219364D01*
G01X258093Y-216564D02*
X254893D01*
G01X262393Y-218298D02*
X263193Y-218964D01*
X264093Y-219364D01*
X264893D01*
X265693Y-218964D01*
X266293Y-218298D01*
X266593Y-217364D01*
X266393Y-216431D01*
X265893Y-215631D01*
X264993Y-215097D01*
X263793Y-214831D01*
X263093Y-214297D01*
X262793Y-213364D01*
X262993Y-212431D01*
X263493Y-211764D01*
X264193Y-211364D01*
X264893D01*
X265593Y-211631D01*
X266193Y-212297D01*
G01X270293Y-219364D02*
Y-211364D01*
G01X274093D02*
X270293Y-216298D01*
G01X274693Y-219364D02*
X271993Y-214031D01*
G01X279193Y-216697D02*
X281793D01*
G01X289293Y-215097D02*
X289693Y-214697D01*
X289993Y-214031D01*
X290193Y-213097D01*
X289993Y-212297D01*
X289593Y-211764D01*
X288893Y-211364D01*
X286193D01*
Y-219364D01*
X289493D01*
X290193Y-218831D01*
X290593Y-218031D01*
X290793Y-217097D01*
X290593Y-216164D01*
X289993Y-215364D01*
X289293Y-215097D01*
X286193D01*
G01X296493Y-219364D02*
X295693Y-219231D01*
X294993Y-218697D01*
X294393Y-217897D01*
X293993Y-216964D01*
X293793Y-215897D01*
Y-214831D01*
X293993Y-213764D01*
X294393Y-212831D01*
X294993Y-212031D01*
X295693Y-211497D01*
X296493Y-211364D01*
X297293Y-211497D01*
X297993Y-212031D01*
X298593Y-212831D01*
X298993Y-213764D01*
X299193Y-214831D01*
Y-215897D01*
X298993Y-216964D01*
X298593Y-217897D01*
X297993Y-218697D01*
X297293Y-219231D01*
X296493Y-219364D01*
G01X304493Y-211364D02*
Y-219364D01*
G01X302193Y-211364D02*
X306793D01*
G01X359093Y-237697D02*
X359693Y-236897D01*
X360393Y-236497D01*
X361193Y-236364D01*
X362193Y-236631D01*
X362893Y-237297D01*
X363093Y-238097D01*
X362993Y-238898D01*
X362593Y-239564D01*
X360593Y-240897D01*
X359693Y-241831D01*
X359093Y-243164D01*
X358893Y-244364D01*
X363093D01*
G01X368993Y-236364D02*
X368193Y-236631D01*
X367593Y-237297D01*
X367193Y-238097D01*
X366893Y-239164D01*
X366793Y-240364D01*
X366893Y-241564D01*
X367193Y-242631D01*
X367593Y-243431D01*
X368193Y-244097D01*
X368993Y-244364D01*
X369793Y-244097D01*
X370393Y-243431D01*
X370793Y-242631D01*
X371093Y-241564D01*
X371193Y-240364D01*
X371093Y-239164D01*
X370793Y-238097D01*
X370393Y-237297D01*
X369793Y-236631D01*
X368993Y-236364D01*
G01X376993Y-244364D02*
Y-236364D01*
X375793Y-237964D01*
G01Y-244364D02*
X378193D01*
G01X383093Y-237697D02*
X383693Y-236897D01*
X384393Y-236497D01*
X385193Y-236364D01*
X386193Y-236631D01*
X386893Y-237297D01*
X387093Y-238097D01*
X386993Y-238898D01*
X386593Y-239564D01*
X384593Y-240897D01*
X383693Y-241831D01*
X383093Y-243164D01*
X382893Y-244364D01*
X387093D01*
G01X391193Y-244631D02*
X394793Y-236364D01*
G01X400993Y-244364D02*
Y-236364D01*
X399793Y-237964D01*
G01Y-244364D02*
X402193D01*
G01X408993Y-236364D02*
X408193Y-236631D01*
X407593Y-237297D01*
X407193Y-238097D01*
X406893Y-239164D01*
X406793Y-240364D01*
X406893Y-241564D01*
X407193Y-242631D01*
X407593Y-243431D01*
X408193Y-244097D01*
X408993Y-244364D01*
X409793Y-244097D01*
X410393Y-243431D01*
X410793Y-242631D01*
X411093Y-241564D01*
X411193Y-240364D01*
X411093Y-239164D01*
X410793Y-238097D01*
X410393Y-237297D01*
X409793Y-236631D01*
X408993Y-236364D01*
G01X415193Y-244631D02*
X418793Y-236364D01*
G01X422793Y-242764D02*
X423393Y-243697D01*
X424193Y-244231D01*
X425093Y-244364D01*
X425893Y-244231D01*
X426693Y-243564D01*
X427193Y-242764D01*
X427293Y-241964D01*
X427093Y-241031D01*
X426393Y-240364D01*
X425693Y-240097D01*
X424793D01*
G01X425693D02*
X426293Y-239697D01*
X426793Y-239031D01*
X426993Y-238231D01*
X426793Y-237431D01*
X426293Y-236764D01*
X425393Y-236364D01*
X424493Y-236497D01*
X423593Y-237031D01*
G01X432993Y-244364D02*
Y-236364D01*
X431793Y-237964D01*
G01Y-244364D02*
X434193D01*
G01X358793Y-219364D02*
Y-211364D01*
X360793D01*
X361593Y-211764D01*
X362193Y-212297D01*
X362693Y-213097D01*
X363093Y-214031D01*
X363193Y-215364D01*
X363093Y-216697D01*
X362693Y-217631D01*
X362193Y-218431D01*
X361593Y-218964D01*
X360793Y-219364D01*
X358793D01*
G01X366493D02*
X368993Y-211364D01*
X371493Y-219364D01*
G01X370593Y-216564D02*
X367393D01*
G01X376993Y-211364D02*
Y-219364D01*
G01X374693Y-211364D02*
X379293D01*
G01X383093Y-216031D02*
X383793Y-215097D01*
X384393Y-214564D01*
X385193Y-214297D01*
X385893Y-214564D01*
X386393Y-215097D01*
X386793Y-215897D01*
X386893Y-216831D01*
X386793Y-217631D01*
X386393Y-218431D01*
X385793Y-219097D01*
X385093Y-219364D01*
X384293Y-219097D01*
X383593Y-218298D01*
X383193Y-217097D01*
X383093Y-215764D01*
X383293Y-214031D01*
X383593Y-213097D01*
X384093Y-212164D01*
X384793Y-211497D01*
X385493Y-211364D01*
X386193Y-211631D01*
X386693Y-212297D01*
G01X390393Y-219364D02*
Y-211364D01*
X392993Y-218031D01*
X395593Y-211364D01*
Y-219364D01*
G01X400993Y-211364D02*
Y-219364D01*
G01X398693Y-211364D02*
X403293D01*
G01X406893Y-219364D02*
Y-211364D01*
G01X411093D02*
Y-219364D01*
G01Y-215364D02*
X406893D01*
G01X414793Y-217764D02*
X415393Y-218697D01*
X416193Y-219231D01*
X417093Y-219364D01*
X417893Y-219231D01*
X418693Y-218564D01*
X419193Y-217764D01*
X419293Y-216964D01*
X419093Y-216031D01*
X418393Y-215364D01*
X417693Y-215097D01*
X416793D01*
G01X417693D02*
X418293Y-214697D01*
X418793Y-214031D01*
X418993Y-213231D01*
X418793Y-212431D01*
X418293Y-211764D01*
X417393Y-211364D01*
X416493Y-211497D01*
X415593Y-212031D01*
G01X422493Y-219364D02*
X424993Y-211364D01*
X427493Y-219364D01*
G01X426593Y-216564D02*
X423393D01*
G01X430793Y-219364D02*
Y-211364D01*
X432793D01*
X433593Y-211764D01*
X434193Y-212297D01*
X434693Y-213097D01*
X435093Y-214031D01*
X435193Y-215364D01*
X435093Y-216697D01*
X434693Y-217631D01*
X434193Y-218431D01*
X433593Y-218964D01*
X432793Y-219364D01*
X430793D01*
G01X440993Y-211364D02*
X440193Y-211631D01*
X439593Y-212297D01*
X439193Y-213097D01*
X438893Y-214164D01*
X438793Y-215364D01*
X438893Y-216564D01*
X439193Y-217631D01*
X439593Y-218431D01*
X440193Y-219097D01*
X440993Y-219364D01*
X441793Y-219097D01*
X442393Y-218431D01*
X442793Y-217631D01*
X443093Y-216564D01*
X443193Y-215364D01*
X443093Y-214164D01*
X442793Y-213097D01*
X442393Y-212297D01*
X441793Y-211631D01*
X440993Y-211364D01*
G01X380993Y-186364D02*
Y-194364D01*
G01X378693Y-186364D02*
X383293D01*
G01X387093Y-191031D02*
X387793Y-190097D01*
X388393Y-189564D01*
X389193Y-189297D01*
X389893Y-189564D01*
X390393Y-190097D01*
X390793Y-190897D01*
X390893Y-191831D01*
X390793Y-192631D01*
X390393Y-193431D01*
X389793Y-194097D01*
X389093Y-194364D01*
X388293Y-194097D01*
X387593Y-193298D01*
X387193Y-192097D01*
X387093Y-190764D01*
X387293Y-189031D01*
X387593Y-188097D01*
X388093Y-187164D01*
X388793Y-186497D01*
X389493Y-186364D01*
X390193Y-186631D01*
X390693Y-187297D01*
G01X394393Y-194364D02*
Y-186364D01*
X396993Y-193031D01*
X399593Y-186364D01*
Y-194364D01*
G01X401993Y-197031D02*
X407993D01*
G01X415193Y-187031D02*
X414593Y-186631D01*
X413893Y-186364D01*
X413093D01*
X412193Y-186764D01*
X411493Y-187431D01*
X410993Y-188231D01*
X410593Y-189564D01*
X410493Y-190764D01*
X410693Y-191964D01*
X410993Y-192764D01*
X411593Y-193564D01*
X412293Y-194097D01*
X412993Y-194364D01*
X413693D01*
X414393Y-194097D01*
X414993Y-193697D01*
X415493Y-193164D01*
G01X418393Y-194364D02*
Y-186364D01*
X420993Y-193031D01*
X423593Y-186364D01*
Y-194364D01*
G01X425993Y-197031D02*
X431993D01*
G01X434793Y-194364D02*
Y-186364D01*
X436793D01*
X437593Y-186764D01*
X438193Y-187297D01*
X438693Y-188097D01*
X439093Y-189031D01*
X439193Y-190364D01*
X439093Y-191697D01*
X438693Y-192631D01*
X438193Y-193431D01*
X437593Y-193964D01*
X436793Y-194364D01*
X434793D01*
G01X473793Y-244364D02*
Y-236364D01*
X475793D01*
X476593Y-236764D01*
X477193Y-237297D01*
X477693Y-238097D01*
X478093Y-239031D01*
X478193Y-240364D01*
X478093Y-241697D01*
X477693Y-242631D01*
X477193Y-243431D01*
X476593Y-243964D01*
X475793Y-244364D01*
X473793D01*
G01X503493D02*
Y-236364D01*
X502293Y-237964D01*
G01Y-244364D02*
X504693D01*
G01X509593Y-241031D02*
X510293Y-240097D01*
X510893Y-239564D01*
X511693Y-239297D01*
X512393Y-239564D01*
X512893Y-240097D01*
X513293Y-240897D01*
X513393Y-241831D01*
X513293Y-242631D01*
X512893Y-243431D01*
X512293Y-244097D01*
X511593Y-244364D01*
X510793Y-244097D01*
X510093Y-243298D01*
X509693Y-242097D01*
X509593Y-240764D01*
X509793Y-239031D01*
X510093Y-238097D01*
X510593Y-237164D01*
X511293Y-236497D01*
X511993Y-236364D01*
X512693Y-236631D01*
X513193Y-237297D01*
G54D26*
X71970Y357848D03*
X147590Y647878D03*
X487770Y513674D03*
X577880Y395242D03*
X693400Y758198D03*
X745580Y62870D03*
G54D53*
X456963Y479623D03*
X465293D03*
X456963Y491223D03*
X465293D03*
G54D62*
X590999Y92789D03*
X615657D03*
G54D17*
X23628Y321764D03*
Y338300D03*
X45282Y321764D03*
G54D35*
X160874Y263034D03*
X159894Y269042D03*
X175200Y265676D03*
X167849Y270242D03*
G54D44*
X264930Y408493D03*
X467880Y569288D03*
G54D54*
X481102Y34528D03*
G54D36*
X156251Y297210D03*
Y303010D03*
X166297Y297499D03*
Y303299D03*
X208947Y343717D03*
Y349517D03*
X203509Y481453D03*
Y487253D03*
X220218Y266687D03*
Y272487D03*
X214447Y343717D03*
Y349517D03*
X218709Y498253D03*
Y492453D03*
X225034Y541049D03*
Y546849D03*
X244201Y326196D03*
Y320396D03*
X251717Y335325D03*
Y341125D03*
X250109Y572109D03*
Y577909D03*
X279004Y494955D03*
Y489155D03*
X291199Y494792D03*
Y488992D03*
X284724Y495518D03*
Y489718D03*
X306221Y79539D03*
Y85339D03*
X300821Y79539D03*
Y85339D03*
X296735Y487826D03*
Y493626D03*
X435451Y251925D03*
Y257725D03*
X494065Y486325D03*
Y492125D03*
X508438Y484300D03*
Y490100D03*
X683230Y454899D03*
Y460699D03*
X689126Y454965D03*
X694833Y464340D03*
Y470140D03*
X689126Y460765D03*
X695082Y480906D03*
Y486706D03*
G54D45*
X289713Y250180D03*
X289959Y246800D03*
G54D27*
X76880Y143269D03*
X739968Y29361D03*
G54D18*
X36024Y187233D03*
Y181225D03*
Y205257D03*
Y199249D03*
Y193241D03*
Y217272D03*
Y211264D03*
X41930Y178221D03*
Y202253D03*
Y196245D03*
Y190237D03*
Y220276D03*
Y214268D03*
Y208260D03*
G54D63*
X605796Y165160D03*
X609733Y215672D03*
G54D37*
X161109Y564853D03*
X155309D03*
X203012Y492651D03*
X208812D03*
X227734Y486164D03*
X221934D03*
X254413Y117582D03*
X260213D03*
X271977Y546643D03*
X277777D03*
X323957Y117410D03*
X329757D03*
X424400Y541007D03*
X430200D03*
X492380Y594236D03*
X507902Y455990D03*
X504538Y556925D03*
X510338D03*
Y562425D03*
X504538D03*
X498180Y594236D03*
X513702Y455990D03*
X542879Y411620D03*
X548679D03*
X683395Y468030D03*
X677595D03*
X679461Y485834D03*
X673661D03*
X679461Y480334D03*
X673661D03*
X679461Y474834D03*
X673661D03*
X697759Y475492D03*
X686720Y475042D03*
X692520D03*
X706395Y468130D03*
X712195D03*
X706395Y462530D03*
X712195D03*
X703559Y475492D03*
G54D55*
X504941Y213711D03*
X507500D03*
X510059D03*
X504941Y221289D03*
X510059D03*
G54D64*
X605796Y174845D03*
G54D28*
X86880Y143269D03*
X749968Y29361D03*
G54D46*
X354348Y38554D03*
X393718D03*
X712975Y155655D03*
Y165455D03*
Y173455D03*
Y183255D03*
Y234461D03*
Y244261D03*
Y252261D03*
Y262061D03*
X723275Y165455D03*
Y173455D03*
Y183255D03*
Y244261D03*
Y252261D03*
Y262061D03*
G54D19*
X40749Y150808D03*
Y249194D03*
G54D29*
X98426Y105512D03*
Y719685D03*
G54D56*
X507489Y281538D03*
G54D65*
X605796Y189845D03*
Y204845D03*
X611702Y185690D03*
Y178997D03*
Y200690D03*
Y193997D03*
G54D38*
X160181Y639044D03*
X165803Y643805D03*
X274538Y562523D03*
X284168Y547993D03*
X296338Y548763D03*
X300848Y556253D03*
X399606Y377165D03*
X413386Y363385D03*
X403543Y367322D03*
Y387008D03*
X413386Y390945D03*
X427166Y377165D03*
X423229Y367322D03*
Y387008D03*
X631522Y782841D03*
X635662Y772045D03*
X643417Y568945D03*
X651262Y783605D03*
X654141Y571687D03*
X657482Y782805D03*
G54D47*
X378012Y805904D03*
X736282D03*
G54D48*
X401329Y650598D03*
Y658078D03*
X391683D03*
Y654338D03*
Y650598D03*
G54D57*
X502390Y628829D03*
X506390Y637629D03*
X498390D03*
X520782Y629598D03*
X524782Y638398D03*
X528782Y629598D03*
X619202Y651970D03*
X636938Y653637D03*
X623202Y660770D03*
X627202Y651970D03*
X632938Y662437D03*
X640938D03*
G54D66*
X638148Y419286D03*
Y426372D03*
G54D39*
X193856Y252341D03*
G54D67*
X688977Y105315D03*
Y719488D03*
G54D49*
X396411Y664578D03*
Y669696D03*
X403989Y664578D03*
Y667137D03*
Y669696D03*
X523611Y218900D03*
Y216341D03*
Y221459D03*
X531189Y216341D03*
Y221459D03*
G54D58*
X514780Y28803D03*
X524780D03*
X514780Y38803D03*
X524780D03*
X534780Y28803D03*
X544780D03*
X534780Y38803D03*
X544780D03*
X554780Y28803D03*
X577371D03*
X587371D03*
X577371Y38803D03*
X587371D03*
X597371Y28803D03*
X607371D03*
X597371Y38803D03*
X607371D03*
X617371Y28803D03*
X639963D03*
Y38803D03*
X649963Y28803D03*
Y38803D03*
X659963Y28803D03*
X669963D03*
X659963Y38803D03*
X669963D03*
X679963Y28803D03*
G54D68*
X711575Y143555D03*
Y195355D03*
Y222361D03*
Y274161D03*
X733975Y143555D03*
Y195355D03*
Y222361D03*
Y274161D03*
G54D59*
X554780Y38803D03*
X617371D03*
X679963D03*
G54D69*
X723275Y155655D03*
Y234461D03*
M02*
